FILE_TYPE = MACRO_DRAWING;
SET COLOR_WIRE YELLOW;
SET COLOR_PROP MONO;
SET COLOR_DOT WHITE;
SET COLOR_ARC YELLOW;
SET COLOR_BODY GREEN;
SET COLOR_NOTE MONO;
SET PROP_DISPLAY VALUE;
SET PAGE_NUMBER P198;
FORCEADD SLG55021..1
(-7000 3825);
FORCEPROP 2 LASTPIN (-7300 3975) $PN 1
J 2
(-7310 3985);
DISPLAY 0.617021 (-7310 3985);
PAINT MONO (-7310 3985);
FORCEPROP 2 LASTPIN (-7300 3775) $PN 3
J 2
(-7310 3785);
DISPLAY 0.617021 (-7310 3785);
PAINT MONO (-7310 3785);
FORCEPROP 2 LASTPIN (-7300 3875) $PN 2
J 2
(-7310 3885);
DISPLAY 0.617021 (-7310 3885);
PAINT MONO (-7310 3885);
FORCEPROP 1 LAST PART_NUMBER G56246-001
J 0
(-7250 3525);
DISPLAY 0.617021 (-7250 3525);
PAINT BLUE (-7250 3525);
FORCEPROP 2 LASTPIN (-6700 3775) $PN 6
J 0
(-6690 3785);
DISPLAY 0.617021 (-6690 3785);
PAINT MONO (-6690 3785);
FORCEPROP 2 LASTPIN (-6700 3625) $PN 9
J 0
(-6690 3635);
DISPLAY 0.617021 (-6690 3635);
PAINT MONO (-6690 3635);
FORCEPROP 2 LASTPIN (-6700 3675) $PN 4
J 0
(-6690 3685);
DISPLAY 0.617021 (-6690 3685);
PAINT MONO (-6690 3685);
FORCEPROP 2 LASTPIN (-6700 3825) $PN 7
J 0
(-6690 3835);
DISPLAY 0.617021 (-6690 3835);
PAINT MONO (-6690 3835);
FORCEPROP 2 LASTPIN (-6700 3975) $PN 8
J 0
(-6690 3985);
DISPLAY 0.617021 (-6690 3985);
PAINT MONO (-6690 3985);
FORCEPROP 2 LASTPIN (-6700 3875) $PN 5
J 0
(-6690 3885);
DISPLAY 0.617021 (-6690 3885);
PAINT MONO (-6690 3885);
FORCEPROP 1 LAST MATERIAL IC
J 0
(-7250 4125);
DISPLAY 0.617021 (-7250 4125);
PAINT SKYBLUE (-7250 4125);
FORCEPROP 1 LAST LOCATION EU2T1
J 0
(-7250 4175);
DISPLAY 0.617021 (-7250 4175);
PAINT AQUA (-7250 4175);
FORCEPROP 1 LAST CDS_LMAN_SYM_OUTLINE -250,250,250,-250
J 0
(-7000 3825);
DISPLAY 0.468085 (-7000 3825);
PAINT GREEN (-7000 3825);
DISPLAY INVISIBLE (-7000 3825);
FORCEPROP 2 LAST CDS_LIB mstr_vreg
J 0
(-7000 3825);
PAINT ORANGE (-7000 3825);
DISPLAY INVISIBLE (-7000 3825);
FORCEPROP 0 LAST ROOM P3V3_PWR_SWITCH
J 0
(-7250 4275);
DISPLAY 1.021277 (-7250 4275);
PAINT ORANGE (-7250 4275);
DISPLAY INVISIBLE (-7250 4275);
FORCEPROP 2 LAST CDS_LOCATION EU2T1
J 0
(-7250 4175);
DISPLAY 0.617021 (-7250 4175);
PAINT AQUA (-7250 4175);
DISPLAY INVISIBLE (-7250 4175);
FORCEPROP 2 LAST $SEC 1
J 0
(-7250 4225);
PAINT MONO (-7250 4225);
DISPLAY INVISIBLE (-7250 4225);
FORCEPROP 2 LAST CDS_SEC 1
J 0
(-7250 4225);
PAINT MONO (-7250 4225);
DISPLAY INVISIBLE (-7250 4225);
FORCEPROP 1 LAST PACK_TYPE SM
J 0
(-7250 4225);
PAINT SKYBLUE (-7250 4225);
DISPLAY INVISIBLE (-7250 4225);
FORCEPROP 1 LAST PATH I1
J 0
(-7000 4125);
PAINT GREEN (-7000 4125);
DISPLAY INVISIBLE (-7000 4125);
FORCEADD GND..1
(-2775 3425);
FORCEPROP 3 LASTPIN (-2775 3475) SIG_NAME GND\g
J 0
(-2765 3485);
DISPLAY 0.659574 (-2765 3485);
PAINT MONO (-2765 3485);
DISPLAY INVISIBLE (-2765 3485);
FORCEPROP 1 LAST PATH I12
J 0
(-2700 3425);
DISPLAY 0.872340 (-2700 3425);
PAINT AQUA (-2700 3425);
DISPLAY INVISIBLE (-2700 3425);
FORCEPROP 1 LAST SIZE 1B
J 0
(-2700 3375);
DISPLAY 1.170213 (-2700 3375);
PAINT AQUA (-2700 3375);
DISPLAY INVISIBLE (-2700 3375);
FORCEPROP 2 LAST CDS_LIB mstr_symbols
J 0
(-2775 3425);
PAINT ORANGE (-2775 3425);
DISPLAY INVISIBLE (-2775 3425);
FORCEPROP 1 LAST VOLTAGE 0.0V
J 0
(-2820 3382);
DISPLAY 0.340426 (-2820 3382);
PAINT SKYBLUE (-2820 3382);
DISPLAY INVISIBLE (-2820 3382);
FORCEPROP 1 LAST BODY_TYPE PLUMBING
J 0
(-2820 3382);
DISPLAY 0.340426 (-2820 3382);
PAINT GREEN (-2820 3382);
DISPLAY INVISIBLE (-2820 3382);
FORCEPROP 1 LAST HDL_POWER GND
J 0
(-2775 3575);
DISPLAY 1.170213 (-2775 3575);
PAINT GREEN (-2775 3575);
DISPLAY INVISIBLE (-2775 3575);
FORCEADD SLG55021..1
(-3300 3800);
FORCEPROP 2 LASTPIN (-3600 3750) $PN 3
J 2
(-3610 3760);
DISPLAY 0.617021 (-3610 3760);
PAINT ORANGE (-3610 3760);
FORCEPROP 2 LASTPIN (-3600 3950) $PN 1
J 2
(-3610 3960);
DISPLAY 0.617021 (-3610 3960);
PAINT ORANGE (-3610 3960);
FORCEPROP 2 LASTPIN (-3600 3850) $PN 2
J 2
(-3610 3860);
DISPLAY 0.617021 (-3610 3860);
PAINT ORANGE (-3610 3860);
FORCEPROP 2 LASTPIN (-3000 3650) $PN 4
J 0
(-2990 3660);
DISPLAY 0.617021 (-2990 3660);
PAINT ORANGE (-2990 3660);
FORCEPROP 2 LASTPIN (-3000 3750) $PN 6
J 0
(-2990 3760);
DISPLAY 0.617021 (-2990 3760);
PAINT ORANGE (-2990 3760);
FORCEPROP 2 LASTPIN (-3000 3800) $PN 7
J 0
(-2990 3810);
DISPLAY 0.617021 (-2990 3810);
PAINT ORANGE (-2990 3810);
FORCEPROP 2 LASTPIN (-3000 3600) $PN 9
J 0
(-2990 3610);
DISPLAY 0.617021 (-2990 3610);
PAINT ORANGE (-2990 3610);
FORCEPROP 2 LASTPIN (-3000 3850) $PN 5
J 0
(-2990 3860);
DISPLAY 0.617021 (-2990 3860);
PAINT ORANGE (-2990 3860);
FORCEPROP 1 LAST MATERIAL IC
J 0
(-3550 4100);
DISPLAY 0.617021 (-3550 4100);
PAINT SKYBLUE (-3550 4100);
FORCEPROP 1 LAST LOCATION EU8B1
J 0
(-3550 4150);
DISPLAY 0.617021 (-3550 4150);
PAINT AQUA (-3550 4150);
FORCEPROP 2 LASTPIN (-3000 3950) $PN 8
J 0
(-2990 3960);
DISPLAY 0.617021 (-2990 3960);
PAINT ORANGE (-2990 3960);
FORCEPROP 1 LAST PART_NUMBER G56246-001
J 0
(-3550 3500);
DISPLAY 0.617021 (-3550 3500);
PAINT BLUE (-3550 3500);
FORCEPROP 2 LAST CDS_LIB mstr_vreg
J 0
(-3300 3800);
PAINT ORANGE (-3300 3800);
DISPLAY INVISIBLE (-3300 3800);
FORCEPROP 1 LAST CDS_LMAN_SYM_OUTLINE -250,250,250,-250
J 0
(-3300 3800);
DISPLAY 0.468085 (-3300 3800);
PAINT GREEN (-3300 3800);
DISPLAY INVISIBLE (-3300 3800);
FORCEPROP 0 LAST ROOM P5V_PWR_SWITCH
J 0
(-3550 4250);
DISPLAY 1.021277 (-3550 4250);
PAINT ORANGE (-3550 4250);
DISPLAY INVISIBLE (-3550 4250);
FORCEPROP 1 LAST PACK_TYPE SM
J 0
(-3550 4200);
PAINT SKYBLUE (-3550 4200);
DISPLAY INVISIBLE (-3550 4200);
FORCEPROP 1 LAST PATH I13
J 0
(-3300 4100);
PAINT GREEN (-3300 4100);
DISPLAY INVISIBLE (-3300 4100);
FORCEPROP 2 LAST CDS_LOCATION EU8B1
J 0
(-3550 4150);
DISPLAY 0.617021 (-3550 4150);
PAINT AQUA (-3550 4150);
DISPLAY INVISIBLE (-3550 4150);
FORCEPROP 2 LAST SEC 1
J 0
(-3550 4200);
DISPLAY 0.680851 (-3550 4200);
PAINT MONO (-3550 4200);
DISPLAY INVISIBLE (-3550 4200);
FORCEPROP 2 LAST SEC_TYPE SM
J 0
(-3550 4200);
DISPLAY 1.021277 (-3550 4200);
PAINT ORANGE (-3550 4200);
DISPLAY INVISIBLE (-3550 4200);
FORCEADD P5V_STBY..1
(-7375 2525);
FORCEPROP 3 LASTPIN (-7375 2475) SIG_NAME P5V_STBY\g
J 0
(-7365 2485);
DISPLAY 0.659574 (-7365 2485);
PAINT MONO (-7365 2485);
DISPLAY INVISIBLE (-7365 2485);
FORCEPROP 1 LAST VOLTAGE 5.0V
J 0
(-7420 2482);
DISPLAY 0.340426 (-7420 2482);
PAINT SKYBLUE (-7420 2482);
DISPLAY INVISIBLE (-7420 2482);
FORCEPROP 1 LAST PATH I15
J 0
(-7330 2527);
DISPLAY 0.340426 (-7330 2527);
PAINT GREEN (-7330 2527);
DISPLAY INVISIBLE (-7330 2527);
FORCEPROP 1 LAST SIZE 1B
J 0
(-7330 2547);
DISPLAY 0.340426 (-7330 2547);
PAINT GREEN (-7330 2547);
DISPLAY INVISIBLE (-7330 2547);
FORCEPROP 2 LAST CDS_LIB mstr_symbols
J 0
(-7375 2525);
PAINT ORANGE (-7375 2525);
DISPLAY INVISIBLE (-7375 2525);
FORCEPROP 1 LAST BODY_TYPE PLUMBING
J 0
(-7420 2482);
DISPLAY 0.340426 (-7420 2482);
PAINT GREEN (-7420 2482);
DISPLAY INVISIBLE (-7420 2482);
FORCEPROP 1 LAST HDL_POWER P5V_STBY
J 0
(-7675 2400);
DISPLAY 0.872340 (-7675 2400);
PAINT ORANGE (-7675 2400);
DISPLAY INVISIBLE (-7675 2400);
FORCEADD GND..1
(-6200 1475);
FORCEPROP 3 LASTPIN (-6200 1525) SIG_NAME GND\g
J 0
(-6190 1535);
DISPLAY 0.659574 (-6190 1535);
PAINT MONO (-6190 1535);
DISPLAY INVISIBLE (-6190 1535);
FORCEPROP 2 LAST CDS_LIB mstr_symbols
J 0
(-6200 1475);
PAINT ORANGE (-6200 1475);
DISPLAY INVISIBLE (-6200 1475);
FORCEPROP 1 LAST VOLTAGE 0.0V
J 0
(-6245 1432);
DISPLAY 0.340426 (-6245 1432);
PAINT SKYBLUE (-6245 1432);
DISPLAY INVISIBLE (-6245 1432);
FORCEPROP 1 LAST PATH I18
J 0
(-6125 1475);
DISPLAY 0.872340 (-6125 1475);
PAINT AQUA (-6125 1475);
DISPLAY INVISIBLE (-6125 1475);
FORCEPROP 1 LAST SIZE 1B
J 0
(-6125 1425);
DISPLAY 1.170213 (-6125 1425);
PAINT AQUA (-6125 1425);
DISPLAY INVISIBLE (-6125 1425);
FORCEPROP 1 LAST BODY_TYPE PLUMBING
J 0
(-6245 1432);
DISPLAY 0.340426 (-6245 1432);
PAINT GREEN (-6245 1432);
DISPLAY INVISIBLE (-6245 1432);
FORCEPROP 1 LAST HDL_POWER GND
J 0
(-6200 1625);
DISPLAY 1.170213 (-6200 1625);
PAINT GREEN (-6200 1625);
DISPLAY INVISIBLE (-6200 1625);
FORCEADD SLG55021..1
(-6725 1850);
FORCEPROP 2 LASTPIN (-7025 1800) $PN 3
J 2
(-7035 1810);
DISPLAY 0.617021 (-7035 1810);
PAINT ORANGE (-7035 1810);
FORCEPROP 2 LASTPIN (-7025 2000) $PN 1
J 2
(-7035 2010);
DISPLAY 0.617021 (-7035 2010);
PAINT ORANGE (-7035 2010);
FORCEPROP 2 LASTPIN (-6425 1900) $PN 5
J 0
(-6415 1910);
DISPLAY 0.617021 (-6415 1910);
PAINT ORANGE (-6415 1910);
FORCEPROP 2 LASTPIN (-6425 1850) $PN 7
J 0
(-6415 1860);
DISPLAY 0.617021 (-6415 1860);
PAINT ORANGE (-6415 1860);
FORCEPROP 2 LASTPIN (-6425 1700) $PN 4
J 0
(-6415 1710);
DISPLAY 0.617021 (-6415 1710);
PAINT ORANGE (-6415 1710);
FORCEPROP 2 LASTPIN (-6425 2000) $PN 8
J 0
(-6415 2010);
DISPLAY 0.617021 (-6415 2010);
PAINT ORANGE (-6415 2010);
FORCEPROP 2 LASTPIN (-6425 1800) $PN 6
J 0
(-6415 1810);
DISPLAY 0.617021 (-6415 1810);
PAINT ORANGE (-6415 1810);
FORCEPROP 2 LASTPIN (-6425 1650) $PN 9
J 0
(-6415 1660);
DISPLAY 0.617021 (-6415 1660);
PAINT ORANGE (-6415 1660);
FORCEPROP 1 LAST MATERIAL IC
J 0
(-6975 2150);
DISPLAY 0.617021 (-6975 2150);
PAINT SKYBLUE (-6975 2150);
FORCEPROP 1 LAST LOCATION EU7E1
J 0
(-6975 2200);
DISPLAY 0.617021 (-6975 2200);
PAINT AQUA (-6975 2200);
FORCEPROP 1 LAST PART_NUMBER G56246-001
J 0
(-6975 1550);
DISPLAY 0.617021 (-6975 1550);
PAINT BLUE (-6975 1550);
FORCEPROP 2 LASTPIN (-7025 1900) $PN 2
J 2
(-7035 1910);
DISPLAY 0.617021 (-7035 1910);
PAINT ORANGE (-7035 1910);
FORCEPROP 1 LAST CDS_LMAN_SYM_OUTLINE -250,250,250,-250
J 0
(-6725 1850);
DISPLAY 0.468085 (-6725 1850);
PAINT GREEN (-6725 1850);
DISPLAY INVISIBLE (-6725 1850);
FORCEPROP 2 LAST CDS_LIB mstr_vreg
J 0
(-6725 1850);
PAINT ORANGE (-6725 1850);
DISPLAY INVISIBLE (-6725 1850);
FORCEPROP 0 LAST ROOM P12V_PWR_SWITCH
J 0
(-6975 2300);
DISPLAY 1.021277 (-6975 2300);
PAINT ORANGE (-6975 2300);
DISPLAY INVISIBLE (-6975 2300);
FORCEPROP 2 LAST CDS_LOCATION EU7E1
J 0
(-6975 2200);
DISPLAY 0.617021 (-6975 2200);
PAINT AQUA (-6975 2200);
DISPLAY INVISIBLE (-6975 2200);
FORCEPROP 2 LAST SEC 1
J 0
(-6975 2250);
DISPLAY 0.680851 (-6975 2250);
PAINT MONO (-6975 2250);
DISPLAY INVISIBLE (-6975 2250);
FORCEPROP 2 LAST SEC_TYPE SM
J 0
(-6975 2250);
DISPLAY 1.021277 (-6975 2250);
PAINT ORANGE (-6975 2250);
DISPLAY INVISIBLE (-6975 2250);
FORCEPROP 1 LAST PACK_TYPE SM
J 0
(-6975 2250);
PAINT SKYBLUE (-6975 2250);
DISPLAY INVISIBLE (-6975 2250);
FORCEPROP 1 LAST PATH I19
J 0
(-6725 2150);
PAINT GREEN (-6725 2150);
DISPLAY INVISIBLE (-6725 2150);
FORCEADD P5V_STBY..1
(-7650 4525);
FORCEPROP 3 LASTPIN (-7650 4475) SIG_NAME P5V_STBY\g
J 0
(-7640 4485);
DISPLAY 0.659574 (-7640 4485);
PAINT MONO (-7640 4485);
DISPLAY INVISIBLE (-7640 4485);
FORCEPROP 1 LAST VOLTAGE 5.0V
J 0
(-7695 4482);
DISPLAY 0.340426 (-7695 4482);
PAINT SKYBLUE (-7695 4482);
DISPLAY INVISIBLE (-7695 4482);
FORCEPROP 1 LAST SIZE 1B
J 0
(-7605 4547);
DISPLAY 0.340426 (-7605 4547);
PAINT GREEN (-7605 4547);
DISPLAY INVISIBLE (-7605 4547);
FORCEPROP 2 LAST CDS_LIB mstr_symbols
J 0
(-7650 4525);
PAINT ORANGE (-7650 4525);
DISPLAY INVISIBLE (-7650 4525);
FORCEPROP 1 LAST PATH I2
J 0
(-7605 4527);
DISPLAY 0.340426 (-7605 4527);
PAINT GREEN (-7605 4527);
DISPLAY INVISIBLE (-7605 4527);
FORCEPROP 1 LAST BODY_TYPE PLUMBING
J 0
(-7695 4482);
DISPLAY 0.340426 (-7695 4482);
PAINT GREEN (-7695 4482);
DISPLAY INVISIBLE (-7695 4482);
FORCEPROP 1 LAST HDL_POWER P5V_STBY
J 0
(-7950 4400);
DISPLAY 0.872340 (-7950 4400);
PAINT ORANGE (-7950 4400);
DISPLAY INVISIBLE (-7950 4400);
FORCEADD P5V_STBY..1
(-1600 4725);
FORCEPROP 3 LASTPIN (-1600 4675) SIG_NAME P5V_STBY\g
J 0
(-1590 4685);
DISPLAY 0.659574 (-1590 4685);
PAINT MONO (-1590 4685);
DISPLAY INVISIBLE (-1590 4685);
FORCEPROP 1 LAST VOLTAGE 5.0V
J 0
(-1645 4682);
DISPLAY 0.340426 (-1645 4682);
PAINT SKYBLUE (-1645 4682);
DISPLAY INVISIBLE (-1645 4682);
FORCEPROP 1 LAST SIZE 1B
J 0
(-1555 4747);
DISPLAY 0.340426 (-1555 4747);
PAINT GREEN (-1555 4747);
DISPLAY INVISIBLE (-1555 4747);
FORCEPROP 2 LAST CDS_LIB mstr_symbols
J 0
(-1600 4725);
PAINT ORANGE (-1600 4725);
DISPLAY INVISIBLE (-1600 4725);
FORCEPROP 1 LAST PATH I20
J 0
(-1555 4727);
DISPLAY 0.340426 (-1555 4727);
PAINT GREEN (-1555 4727);
DISPLAY INVISIBLE (-1555 4727);
FORCEPROP 1 LAST BODY_TYPE PLUMBING
J 0
(-1645 4682);
DISPLAY 0.340426 (-1645 4682);
PAINT GREEN (-1645 4682);
DISPLAY INVISIBLE (-1645 4682);
FORCEPROP 1 LAST HDL_POWER P5V_STBY
J 0
(-1900 4600);
DISPLAY 0.872340 (-1900 4600);
PAINT ORANGE (-1900 4600);
DISPLAY INVISIBLE (-1900 4600);
FORCEADD P5V..1
(-1100 3600);
FORCEPROP 3 LASTPIN (-1100 3550) SIG_NAME P5V\g
J 0
(-1090 3560);
DISPLAY 0.659574 (-1090 3560);
PAINT MONO (-1090 3560);
DISPLAY INVISIBLE (-1090 3560);
FORCEPROP 1 LAST PATH I21
J 0
(-1055 3602);
DISPLAY 0.340426 (-1055 3602);
PAINT GREEN (-1055 3602);
DISPLAY INVISIBLE (-1055 3602);
FORCEPROP 1 LAST SIZE 1B
J 0
(-1055 3622);
DISPLAY 0.340426 (-1055 3622);
PAINT GREEN (-1055 3622);
DISPLAY INVISIBLE (-1055 3622);
FORCEPROP 2 LAST CDS_LIB mstr_symbols
J 0
(-1100 3600);
PAINT ORANGE (-1100 3600);
DISPLAY INVISIBLE (-1100 3600);
FORCEPROP 1 LAST VOLTAGE +5.0V
J 0
(-1025 3750);
DISPLAY 1.021277 (-1025 3750);
PAINT SKYBLUE (-1025 3750);
DISPLAY INVISIBLE (-1025 3750);
FORCEPROP 1 LAST BODY_TYPE PLUMBING
J 0
(-1145 3557);
DISPLAY 0.340426 (-1145 3557);
PAINT GREEN (-1145 3557);
DISPLAY INVISIBLE (-1145 3557);
FORCEPROP 1 LAST HDL_POWER P5V
J 0
(-1400 3475);
DISPLAY 0.872340 (-1400 3475);
PAINT ORANGE (-1400 3475);
DISPLAY INVISIBLE (-1400 3475);
FORCEADD P12V..1
(-4675 1625);
FORCEPROP 3 LASTPIN (-4675 1575) SIG_NAME P12V\g
J 0
(-4665 1585);
DISPLAY 0.659574 (-4665 1585);
PAINT MONO (-4665 1585);
DISPLAY INVISIBLE (-4665 1585);
FORCEPROP 1 LAST PATH I22
J 0
(-4630 1627);
DISPLAY 0.340426 (-4630 1627);
PAINT GREEN (-4630 1627);
DISPLAY INVISIBLE (-4630 1627);
FORCEPROP 1 LAST SIZE 1B
J 0
(-4630 1647);
DISPLAY 0.340426 (-4630 1647);
PAINT GREEN (-4630 1647);
DISPLAY INVISIBLE (-4630 1647);
FORCEPROP 2 LAST CDS_LIB mstr_symbols
J 0
(-4675 1625);
PAINT ORANGE (-4675 1625);
DISPLAY INVISIBLE (-4675 1625);
FORCEPROP 1 LAST VOLTAGE +12.0V
J 0
(-4575 1775);
DISPLAY 1.021277 (-4575 1775);
PAINT SKYBLUE (-4575 1775);
DISPLAY INVISIBLE (-4575 1775);
FORCEPROP 1 LAST BODY_TYPE PLUMBING
J 0
(-4720 1582);
DISPLAY 0.340426 (-4720 1582);
PAINT GREEN (-4720 1582);
DISPLAY INVISIBLE (-4720 1582);
FORCEPROP 1 LAST HDL_POWER P12V
J 0
(-4875 1475);
DISPLAY 0.872340 (-4875 1475);
PAINT ORANGE (-4875 1475);
DISPLAY INVISIBLE (-4875 1475);
FORCEADD P12V_STBY..1
(-5325 2575);
FORCEPROP 3 LASTPIN (-5325 2525) SIG_NAME P12V_STBY\g
J 0
(-5315 2535);
DISPLAY 0.659574 (-5315 2535);
PAINT MONO (-5315 2535);
DISPLAY INVISIBLE (-5315 2535);
FORCEPROP 1 LAST VOLTAGE 12.0V
J 0
(-5370 2532);
DISPLAY 0.340426 (-5370 2532);
PAINT SKYBLUE (-5370 2532);
DISPLAY INVISIBLE (-5370 2532);
FORCEPROP 1 LAST PATH I23
J 0
(-5280 2577);
DISPLAY 0.340426 (-5280 2577);
PAINT GREEN (-5280 2577);
DISPLAY INVISIBLE (-5280 2577);
FORCEPROP 1 LAST SIZE 1B
J 0
(-5280 2597);
DISPLAY 0.340426 (-5280 2597);
PAINT GREEN (-5280 2597);
DISPLAY INVISIBLE (-5280 2597);
FORCEPROP 2 LAST CDS_LIB mstr_symbols
J 0
(-5325 2575);
PAINT ORANGE (-5325 2575);
DISPLAY INVISIBLE (-5325 2575);
FORCEPROP 1 LAST BODY_TYPE PLUMBING
J 0
(-5370 2532);
DISPLAY 0.340426 (-5370 2532);
PAINT GREEN (-5370 2532);
DISPLAY INVISIBLE (-5370 2532);
FORCEPROP 1 LAST HDL_POWER P12V_STBY
J 0
(-5625 2450);
DISPLAY 0.872340 (-5625 2450);
PAINT ORANGE (-5625 2450);
DISPLAY INVISIBLE (-5625 2450);
FORCEADD CAP_A..1
(-8000 4200);
FORCEPROP 1 LAST PACK_TYPE 0402V
J 0
(-7950 4000);
DISPLAY 0.617021 (-7950 4000);
PAINT SKYBLUE (-7950 4000);
FORCEPROP 1 LAST PART_NUMBER A36096-030
J 0
(-7950 4050);
DISPLAY 0.617021 (-7950 4050);
PAINT BLUE (-7950 4050);
FORCEPROP 1 LASTPIN (-8000 4100) $PN 2
J 0
(-7990 4080);
DISPLAY 0.617021 (-7990 4080);
PAINT ORANGE (-7990 4080);
FORCEPROP 1 LASTPIN (-8000 4300) $PN 1
J 0
(-7990 4280);
DISPLAY 0.617021 (-7990 4280);
PAINT ORANGE (-7990 4280);
FORCEPROP 1 LAST MATERIAL X7R
J 0
(-7950 4100);
DISPLAY 0.617021 (-7950 4100);
PAINT SKYBLUE (-7950 4100);
FORCEPROP 1 LAST VOLTAGE 16V
J 0
(-7950 4200);
DISPLAY 0.617021 (-7950 4200);
PAINT SKYBLUE (-7950 4200);
FORCEPROP 1 LAST TOLERANCE 10%
J 0
(-7950 4150);
DISPLAY 0.617021 (-7950 4150);
PAINT SKYBLUE (-7950 4150);
FORCEPROP 1 LAST VALUE 0.1UF
J 0
(-7950 4250);
DISPLAY 0.617021 (-7950 4250);
PAINT SKYBLUE (-7950 4250);
FORCEPROP 1 LAST LOCATION C8F17
J 0
(-7950 4300);
DISPLAY 0.617021 (-7950 4300);
PAINT AQUA (-7950 4300);
FORCEPROP 2 LAST CDS_LIB dev_discrete
J 0
(-8000 4200);
PAINT ORANGE (-8000 4200);
DISPLAY INVISIBLE (-8000 4200);
FORCEPROP 2 LAST CDS_LOCATION C8F17
J 0
(-7950 4300);
DISPLAY 0.617021 (-7950 4300);
PAINT AQUA (-7950 4300);
DISPLAY INVISIBLE (-7950 4300);
FORCEPROP 1 LAST PATH I24
J 0
(-7950 4350);
DISPLAY 0.978723 (-7950 4350);
PAINT WHITE (-7950 4350);
DISPLAY INVISIBLE (-7950 4350);
FORCEPROP 2 LAST CDS_SEC 1
J 0
(-7950 4350);
PAINT ORANGE (-7950 4350);
DISPLAY INVISIBLE (-7950 4350);
FORCEPROP 0 LAST ROOM P3V3_PWR_SWITCH
J 0
(-7950 4400);
DISPLAY 1.021277 (-7950 4400);
PAINT ORANGE (-7950 4400);
DISPLAY INVISIBLE (-7950 4400);
FORCEPROP 2 LAST SEC_TYPE 0402V
J 0
(-7950 4400);
DISPLAY 1.021277 (-7950 4400);
PAINT ORANGE (-7950 4400);
DISPLAY INVISIBLE (-7950 4400);
FORCEPROP 2 LAST SEC 1
J 0
(-7950 4400);
DISPLAY 0.680851 (-7950 4400);
PAINT MONO (-7950 4400);
DISPLAY INVISIBLE (-7950 4400);
FORCEADD GND..1
(-8000 4000);
FORCEPROP 3 LASTPIN (-8000 4050) SIG_NAME GND\g
J 0
(-7990 4060);
DISPLAY 0.659574 (-7990 4060);
PAINT MONO (-7990 4060);
DISPLAY INVISIBLE (-7990 4060);
FORCEPROP 2 LAST CDS_LIB mstr_symbols
J 0
(-8000 4000);
PAINT ORANGE (-8000 4000);
DISPLAY INVISIBLE (-8000 4000);
FORCEPROP 1 LAST VOLTAGE 0.0V
J 0
(-8045 3957);
DISPLAY 0.340426 (-8045 3957);
PAINT SKYBLUE (-8045 3957);
DISPLAY INVISIBLE (-8045 3957);
FORCEPROP 1 LAST PATH I25
J 0
(-7925 4000);
DISPLAY 0.872340 (-7925 4000);
PAINT AQUA (-7925 4000);
DISPLAY INVISIBLE (-7925 4000);
FORCEPROP 1 LAST SIZE 1B
J 0
(-7925 3950);
DISPLAY 1.170213 (-7925 3950);
PAINT AQUA (-7925 3950);
DISPLAY INVISIBLE (-7925 3950);
FORCEPROP 1 LAST BODY_TYPE PLUMBING
J 0
(-8045 3957);
DISPLAY 0.340426 (-8045 3957);
PAINT GREEN (-8045 3957);
DISPLAY INVISIBLE (-8045 3957);
FORCEPROP 1 LAST HDL_POWER GND
J 0
(-8000 4150);
DISPLAY 1.170213 (-8000 4150);
PAINT GREEN (-8000 4150);
DISPLAY INVISIBLE (-8000 4150);
FORCEADD CAP_A..1
(-4300 4125);
FORCEPROP 1 LASTPIN (-4300 4025) $PN 2
J 0
(-4290 4005);
DISPLAY 0.617021 (-4290 4005);
PAINT ORANGE (-4290 4005);
FORCEPROP 1 LAST MATERIAL X7R
J 0
(-4250 4025);
DISPLAY 0.617021 (-4250 4025);
PAINT SKYBLUE (-4250 4025);
FORCEPROP 1 LASTPIN (-4300 4225) $PN 1
J 0
(-4290 4205);
DISPLAY 0.617021 (-4290 4205);
PAINT ORANGE (-4290 4205);
FORCEPROP 1 LAST PART_NUMBER A36096-030
J 0
(-4250 3975);
DISPLAY 0.617021 (-4250 3975);
PAINT BLUE (-4250 3975);
FORCEPROP 1 LAST TOLERANCE 10%
J 0
(-4250 4075);
DISPLAY 0.617021 (-4250 4075);
PAINT SKYBLUE (-4250 4075);
FORCEPROP 1 LAST VOLTAGE 16V
J 0
(-4250 4125);
DISPLAY 0.617021 (-4250 4125);
PAINT SKYBLUE (-4250 4125);
FORCEPROP 1 LAST PACK_TYPE 0402V
J 0
(-4250 3925);
DISPLAY 0.617021 (-4250 3925);
PAINT SKYBLUE (-4250 3925);
FORCEPROP 1 LAST LOCATION C8B8
J 0
(-4500 4125);
DISPLAY 0.617021 (-4500 4125);
PAINT AQUA (-4500 4125);
FORCEPROP 1 LAST VALUE 0.1UF
J 0
(-4250 4175);
DISPLAY 0.617021 (-4250 4175);
PAINT SKYBLUE (-4250 4175);
FORCEPROP 2 LAST CDS_LOCATION C8B8
J 0
(-4500 4125);
DISPLAY 0.617021 (-4500 4125);
PAINT AQUA (-4500 4125);
DISPLAY INVISIBLE (-4500 4125);
FORCEPROP 2 LAST CDS_LIB dev_discrete
J 0
(-4300 4125);
PAINT ORANGE (-4300 4125);
DISPLAY INVISIBLE (-4300 4125);
FORCEPROP 1 LAST PATH I26
J 0
(-4250 4275);
DISPLAY 0.978723 (-4250 4275);
PAINT WHITE (-4250 4275);
DISPLAY INVISIBLE (-4250 4275);
FORCEPROP 0 LAST ROOM P5V_PWR_SWITCH
J 0
(-4250 4275);
DISPLAY 1.021277 (-4250 4275);
PAINT ORANGE (-4250 4275);
DISPLAY INVISIBLE (-4250 4275);
FORCEPROP 2 LAST CDS_SEC 1
J 0
(-4250 4225);
PAINT ORANGE (-4250 4225);
DISPLAY INVISIBLE (-4250 4225);
FORCEPROP 2 LAST SEC_TYPE 0402V
J 0
(-4250 4325);
DISPLAY 1.021277 (-4250 4325);
PAINT ORANGE (-4250 4325);
DISPLAY INVISIBLE (-4250 4325);
FORCEPROP 2 LAST SEC 1
J 0
(-4250 4325);
DISPLAY 0.680851 (-4250 4325);
PAINT MONO (-4250 4325);
DISPLAY INVISIBLE (-4250 4325);
FORCEADD GND..1
(-4300 3950);
FORCEPROP 3 LASTPIN (-4300 4000) SIG_NAME GND\g
J 0
(-4290 4010);
DISPLAY 0.659574 (-4290 4010);
PAINT MONO (-4290 4010);
DISPLAY INVISIBLE (-4290 4010);
FORCEPROP 1 LAST VOLTAGE 0.0V
J 0
(-4345 3907);
DISPLAY 0.340426 (-4345 3907);
PAINT SKYBLUE (-4345 3907);
DISPLAY INVISIBLE (-4345 3907);
FORCEPROP 1 LAST SIZE 1B
J 0
(-4225 3900);
DISPLAY 1.170213 (-4225 3900);
PAINT AQUA (-4225 3900);
DISPLAY INVISIBLE (-4225 3900);
FORCEPROP 2 LAST CDS_LIB mstr_symbols
J 0
(-4300 3950);
PAINT ORANGE (-4300 3950);
DISPLAY INVISIBLE (-4300 3950);
FORCEPROP 1 LAST PATH I27
J 0
(-4225 3950);
DISPLAY 0.872340 (-4225 3950);
PAINT AQUA (-4225 3950);
DISPLAY INVISIBLE (-4225 3950);
FORCEPROP 1 LAST BODY_TYPE PLUMBING
J 0
(-4345 3907);
DISPLAY 0.340426 (-4345 3907);
PAINT GREEN (-4345 3907);
DISPLAY INVISIBLE (-4345 3907);
FORCEPROP 1 LAST HDL_POWER GND
J 0
(-4300 4100);
DISPLAY 1.170213 (-4300 4100);
PAINT GREEN (-4300 4100);
DISPLAY INVISIBLE (-4300 4100);
FORCEADD CAP_A..1
(-7725 2175);
FORCEPROP 1 LAST PACK_TYPE 0402V
J 0
(-7675 1975);
DISPLAY 0.617021 (-7675 1975);
PAINT SKYBLUE (-7675 1975);
FORCEPROP 1 LASTPIN (-7725 2075) $PN 2
J 0
(-7715 2055);
DISPLAY 0.617021 (-7715 2055);
PAINT ORANGE (-7715 2055);
FORCEPROP 1 LASTPIN (-7725 2275) $PN 1
J 0
(-7715 2255);
DISPLAY 0.617021 (-7715 2255);
PAINT ORANGE (-7715 2255);
FORCEPROP 1 LAST TOLERANCE 10%
J 0
(-7675 2125);
DISPLAY 0.617021 (-7675 2125);
PAINT SKYBLUE (-7675 2125);
FORCEPROP 1 LAST VOLTAGE 16V
J 0
(-7675 2175);
DISPLAY 0.617021 (-7675 2175);
PAINT SKYBLUE (-7675 2175);
FORCEPROP 1 LAST MATERIAL X7R
J 0
(-7675 2075);
DISPLAY 0.617021 (-7675 2075);
PAINT SKYBLUE (-7675 2075);
FORCEPROP 1 LAST PART_NUMBER A36096-030
J 0
(-7675 2025);
DISPLAY 0.617021 (-7675 2025);
PAINT BLUE (-7675 2025);
FORCEPROP 1 LAST VALUE 0.1UF
J 0
(-7675 2225);
DISPLAY 0.617021 (-7675 2225);
PAINT SKYBLUE (-7675 2225);
FORCEPROP 1 LAST LOCATION C8E19
J 0
(-7675 2275);
DISPLAY 0.617021 (-7675 2275);
PAINT AQUA (-7675 2275);
FORCEPROP 2 LAST CDS_LIB dev_discrete
J 0
(-7725 2175);
PAINT ORANGE (-7725 2175);
DISPLAY INVISIBLE (-7725 2175);
FORCEPROP 1 LAST PATH I28
J 0
(-7675 2325);
DISPLAY 0.978723 (-7675 2325);
PAINT WHITE (-7675 2325);
DISPLAY INVISIBLE (-7675 2325);
FORCEPROP 0 LAST ROOM P12V_PWR_SWITCH
J 0
(-7675 2375);
DISPLAY 1.021277 (-7675 2375);
PAINT ORANGE (-7675 2375);
DISPLAY INVISIBLE (-7675 2375);
FORCEPROP 2 LAST CDS_SEC 1
J 0
(-7675 2325);
PAINT ORANGE (-7675 2325);
DISPLAY INVISIBLE (-7675 2325);
FORCEPROP 2 LAST SEC_TYPE 0402V
J 0
(-7675 2375);
DISPLAY 1.021277 (-7675 2375);
PAINT ORANGE (-7675 2375);
DISPLAY INVISIBLE (-7675 2375);
FORCEPROP 2 LAST SEC 1
J 0
(-7675 2375);
DISPLAY 0.680851 (-7675 2375);
PAINT MONO (-7675 2375);
DISPLAY INVISIBLE (-7675 2375);
FORCEADD GND..1
(-7725 2000);
FORCEPROP 3 LASTPIN (-7725 2050) SIG_NAME GND\g
J 0
(-7715 2060);
DISPLAY 0.659574 (-7715 2060);
PAINT MONO (-7715 2060);
DISPLAY INVISIBLE (-7715 2060);
FORCEPROP 2 LAST CDS_LIB mstr_symbols
J 0
(-7725 2000);
PAINT ORANGE (-7725 2000);
DISPLAY INVISIBLE (-7725 2000);
FORCEPROP 1 LAST VOLTAGE 0.0V
J 0
(-7770 1957);
DISPLAY 0.340426 (-7770 1957);
PAINT SKYBLUE (-7770 1957);
DISPLAY INVISIBLE (-7770 1957);
FORCEPROP 1 LAST PATH I29
J 0
(-7650 2000);
DISPLAY 0.872340 (-7650 2000);
PAINT AQUA (-7650 2000);
DISPLAY INVISIBLE (-7650 2000);
FORCEPROP 1 LAST SIZE 1B
J 0
(-7650 1950);
DISPLAY 1.170213 (-7650 1950);
PAINT AQUA (-7650 1950);
DISPLAY INVISIBLE (-7650 1950);
FORCEPROP 1 LAST BODY_TYPE PLUMBING
J 0
(-7770 1957);
DISPLAY 0.340426 (-7770 1957);
PAINT GREEN (-7770 1957);
DISPLAY INVISIBLE (-7770 1957);
FORCEPROP 1 LAST HDL_POWER GND
J 0
(-7725 2150);
DISPLAY 1.170213 (-7725 2150);
PAINT GREEN (-7725 2150);
DISPLAY INVISIBLE (-7725 2150);
FORCEADD GND..1
(-6475 3450);
FORCEPROP 3 LASTPIN (-6475 3500) SIG_NAME GND\g
J 0
(-6465 3510);
DISPLAY 0.659574 (-6465 3510);
PAINT MONO (-6465 3510);
DISPLAY INVISIBLE (-6465 3510);
FORCEPROP 1 LAST PATH I3
J 0
(-6400 3450);
DISPLAY 0.872340 (-6400 3450);
PAINT AQUA (-6400 3450);
DISPLAY INVISIBLE (-6400 3450);
FORCEPROP 1 LAST VOLTAGE 0.0V
J 0
(-6520 3407);
DISPLAY 0.340426 (-6520 3407);
PAINT SKYBLUE (-6520 3407);
DISPLAY INVISIBLE (-6520 3407);
FORCEPROP 2 LAST CDS_LIB mstr_symbols
J 0
(-6475 3450);
PAINT ORANGE (-6475 3450);
DISPLAY INVISIBLE (-6475 3450);
FORCEPROP 1 LAST SIZE 1B
J 0
(-6400 3400);
DISPLAY 1.170213 (-6400 3400);
PAINT AQUA (-6400 3400);
DISPLAY INVISIBLE (-6400 3400);
FORCEPROP 1 LAST BODY_TYPE PLUMBING
J 0
(-6520 3407);
DISPLAY 0.340426 (-6520 3407);
PAINT GREEN (-6520 3407);
DISPLAY INVISIBLE (-6520 3407);
FORCEPROP 1 LAST HDL_POWER GND
J 0
(-6475 3600);
DISPLAY 1.170213 (-6475 3600);
PAINT GREEN (-6475 3600);
DISPLAY INVISIBLE (-6475 3600);
FORCEADD OFFPAGE..1
(-7650 2800);
FORCEPROP 2 LAST $XR2 191 
J 0
(-8142 2800);
DISPLAY 0.638298 (-8142 2800);
PAINT MONO (-8142 2800);
FORCEPROP 2 LAST $XR1 161 
J 0
(-8022 2800);
DISPLAY 0.638298 (-8022 2800);
PAINT MONO (-8022 2800);
FORCEPROP 2 LAST $XR0 181 
J 0
(-7902 2800);
DISPLAY 0.638298 (-7902 2800);
PAINT MONO (-7902 2800);
FORCEPROP 2 LAST CDS_LIB mstr_standard
J 0
(-7650 2800);
PAINT ORANGE (-7650 2800);
DISPLAY INVISIBLE (-7650 2800);
FORCEPROP 2 LAST PATH I32
J 0
(-7600 2875);
DISPLAY 1.021277 (-7600 2875);
PAINT ORANGE (-7600 2875);
DISPLAY INVISIBLE (-7600 2875);
FORCEPROP 1 LAST OFFPAGE TRUE
J 0
(-7325 2675);
DISPLAY 1.170213 (-7325 2675);
PAINT GREEN (-7325 2675);
DISPLAY INVISIBLE (-7325 2675);
FORCEPROP 1 LAST COMMENT_BODY TRUE
J 0
(-7525 2700);
DISPLAY 1.170213 (-7525 2700);
PAINT PEACH (-7525 2700);
DISPLAY INVISIBLE (-7525 2700);
FORCEADD CAP_A..1
(-1050 4400);
FORCEPROP 1 LASTPIN (-1050 4300) $PN 2
J 0
(-1040 4280);
DISPLAY 0.617021 (-1040 4280);
PAINT ORANGE (-1040 4280);
FORCEPROP 1 LASTPIN (-1050 4500) $PN 1
J 0
(-1040 4480);
DISPLAY 0.617021 (-1040 4480);
PAINT ORANGE (-1040 4480);
FORCEPROP 1 LAST MATERIAL X7R
J 0
(-1000 4300);
DISPLAY 0.617021 (-1000 4300);
PAINT SKYBLUE (-1000 4300);
FORCEPROP 1 LAST VOLTAGE 16V
J 0
(-1000 4400);
DISPLAY 0.617021 (-1000 4400);
PAINT SKYBLUE (-1000 4400);
FORCEPROP 1 LAST PACK_TYPE 0402V
J 0
(-1000 4200);
DISPLAY 0.617021 (-1000 4200);
PAINT SKYBLUE (-1000 4200);
FORCEPROP 1 LAST TOLERANCE 10%
J 0
(-1000 4350);
DISPLAY 0.617021 (-1000 4350);
PAINT SKYBLUE (-1000 4350);
FORCEPROP 1 LAST VALUE 0.1UF
J 0
(-1000 4450);
DISPLAY 0.617021 (-1000 4450);
PAINT SKYBLUE (-1000 4450);
FORCEPROP 1 LAST PART_NUMBER A36096-030
J 0
(-1000 4250);
DISPLAY 0.617021 (-1000 4250);
PAINT BLUE (-1000 4250);
FORCEPROP 1 LAST LOCATION C8B5
J 0
(-1000 4500);
DISPLAY 0.617021 (-1000 4500);
PAINT AQUA (-1000 4500);
FORCEPROP 2 LAST CDS_LIB dev_discrete
J 0
(-1050 4400);
PAINT ORANGE (-1050 4400);
DISPLAY INVISIBLE (-1050 4400);
FORCEPROP 2 LAST SEC 1
J 0
(-1000 4600);
DISPLAY 0.680851 (-1000 4600);
PAINT MONO (-1000 4600);
DISPLAY INVISIBLE (-1000 4600);
FORCEPROP 2 LAST SEC_TYPE 0402V
J 0
(-1000 4600);
DISPLAY 1.021277 (-1000 4600);
PAINT ORANGE (-1000 4600);
DISPLAY INVISIBLE (-1000 4600);
FORCEPROP 2 LAST CDS_SEC 1
J 0
(-1000 4550);
PAINT ORANGE (-1000 4550);
DISPLAY INVISIBLE (-1000 4550);
FORCEPROP 0 LAST BOM_COST PWR_SWITCH
J 0
(-1000 4700);
DISPLAY 1.021277 (-1000 4700);
PAINT ORANGE (-1000 4700);
DISPLAY INVISIBLE (-1000 4700);
FORCEPROP 2 LAST CDS_LOCATION C8B5
J 0
(-1000 4500);
DISPLAY 0.617021 (-1000 4500);
PAINT AQUA (-1000 4500);
DISPLAY INVISIBLE (-1000 4500);
FORCEPROP 0 LAST ROOM P5V_PWR_SWITCH
J 0
(-1000 4600);
DISPLAY 1.021277 (-1000 4600);
PAINT ORANGE (-1000 4600);
DISPLAY INVISIBLE (-1000 4600);
FORCEPROP 1 LAST PATH I37
J 0
(-1000 4550);
DISPLAY 0.978723 (-1000 4550);
PAINT WHITE (-1000 4550);
DISPLAY INVISIBLE (-1000 4550);
FORCEADD CAP..1
(-1375 4400);
FORCEPROP 1 LASTPIN (-1375 4300) $PN 2
J 0
(-1365 4280);
DISPLAY 0.617021 (-1365 4280);
PAINT ORANGE (-1365 4280);
FORCEPROP 1 LASTPIN (-1375 4500) $PN 1
J 0
(-1365 4480);
DISPLAY 0.617021 (-1365 4480);
PAINT ORANGE (-1365 4480);
FORCEPROP 1 LAST VOLTAGE 16V
J 0
(-1325 4400);
DISPLAY 0.617021 (-1325 4400);
PAINT SKYBLUE (-1325 4400);
FORCEPROP 1 LAST TOLERANCE 10%
J 0
(-1325 4350);
DISPLAY 0.617021 (-1325 4350);
PAINT SKYBLUE (-1325 4350);
FORCEPROP 1 LAST VALUE 10UF
J 0
(-1325 4450);
DISPLAY 0.617021 (-1325 4450);
PAINT SKYBLUE (-1325 4450);
FORCEPROP 1 LAST LOCATION C8B12
J 0
(-1325 4500);
DISPLAY 0.617021 (-1325 4500);
PAINT AQUA (-1325 4500);
FORCEPROP 1 LAST PACK_TYPE 0805
J 0
(-1325 4200);
DISPLAY 0.617021 (-1325 4200);
PAINT SKYBLUE (-1325 4200);
FORCEPROP 1 LAST MATERIAL X6S
J 0
(-1325 4300);
DISPLAY 0.617021 (-1325 4300);
PAINT SKYBLUE (-1325 4300);
FORCEPROP 1 LAST PART_NUMBER C95333-007
J 0
(-1325 4250);
DISPLAY 0.617021 (-1325 4250);
PAINT BLUE (-1325 4250);
FORCEPROP 2 LAST ROOM P5V_PWR_SWITCH
J 0
(-1325 4550);
DISPLAY 1.361702 (-1325 4550);
PAINT ORANGE (-1325 4550);
DISPLAY INVISIBLE (-1325 4550);
FORCEPROP 1 LAST PATH I38
J 0
(-1325 4550);
DISPLAY 0.978723 (-1325 4550);
PAINT WHITE (-1325 4550);
DISPLAY INVISIBLE (-1325 4550);
FORCEPROP 2 LAST CDS_LOCATION C8B12
J 0
(-1325 4500);
DISPLAY 0.617021 (-1325 4500);
PAINT AQUA (-1325 4500);
DISPLAY INVISIBLE (-1325 4500);
FORCEPROP 2 LAST CDS_LIB mstr_discrete
J 0
(-1375 4400);
PAINT ORANGE (-1375 4400);
DISPLAY INVISIBLE (-1375 4400);
FORCEPROP 2 LAST SEC 1
J 0
(-1325 4600);
DISPLAY 0.680851 (-1325 4600);
PAINT MONO (-1325 4600);
DISPLAY INVISIBLE (-1325 4600);
FORCEPROP 2 LAST SEC_TYPE 0805
J 0
(-1325 4600);
DISPLAY 1.021277 (-1325 4600);
PAINT ORANGE (-1325 4600);
DISPLAY INVISIBLE (-1325 4600);
FORCEADD GND..1
(-1200 4075);
FORCEPROP 3 LASTPIN (-1200 4125) SIG_NAME GND\g
J 0
(-1190 4135);
DISPLAY 0.659574 (-1190 4135);
PAINT MONO (-1190 4135);
DISPLAY INVISIBLE (-1190 4135);
FORCEPROP 1 LAST SIZE 1B
J 0
(-1125 4025);
DISPLAY 1.170213 (-1125 4025);
PAINT AQUA (-1125 4025);
DISPLAY INVISIBLE (-1125 4025);
FORCEPROP 1 LAST VOLTAGE 0.0V
J 0
(-1245 4032);
DISPLAY 0.340426 (-1245 4032);
PAINT SKYBLUE (-1245 4032);
DISPLAY INVISIBLE (-1245 4032);
FORCEPROP 1 LAST PATH I39
J 0
(-1125 4075);
DISPLAY 0.872340 (-1125 4075);
PAINT AQUA (-1125 4075);
DISPLAY INVISIBLE (-1125 4075);
FORCEPROP 2 LAST CDS_LIB mstr_symbols
J 0
(-1200 4075);
PAINT ORANGE (-1200 4075);
DISPLAY INVISIBLE (-1200 4075);
FORCEPROP 1 LAST BODY_TYPE PLUMBING
J 0
(-1245 4032);
DISPLAY 0.340426 (-1245 4032);
PAINT GREEN (-1245 4032);
DISPLAY INVISIBLE (-1245 4032);
FORCEPROP 1 LAST HDL_POWER GND
J 0
(-1200 4225);
DISPLAY 1.170213 (-1200 4225);
PAINT GREEN (-1200 4225);
DISPLAY INVISIBLE (-1200 4225);
FORCEADD CAP..1
(-1100 3250);
FORCEPROP 1 LASTPIN (-1100 3150) $PN 2
J 0
(-1090 3130);
DISPLAY 0.617021 (-1090 3130);
PAINT ORANGE (-1090 3130);
FORCEPROP 1 LAST MATERIAL X6S
J 0
(-1050 3150);
DISPLAY 0.617021 (-1050 3150);
PAINT SKYBLUE (-1050 3150);
FORCEPROP 1 LAST VOLTAGE 16V
J 0
(-1050 3250);
DISPLAY 0.617021 (-1050 3250);
PAINT SKYBLUE (-1050 3250);
FORCEPROP 1 LAST PACK_TYPE 0805
J 0
(-1050 3050);
DISPLAY 0.617021 (-1050 3050);
PAINT SKYBLUE (-1050 3050);
FORCEPROP 1 LAST TOLERANCE 10%
J 0
(-1050 3200);
DISPLAY 0.617021 (-1050 3200);
PAINT SKYBLUE (-1050 3200);
FORCEPROP 1 LAST VALUE 10UF
J 0
(-1050 3300);
DISPLAY 0.617021 (-1050 3300);
PAINT SKYBLUE (-1050 3300);
FORCEPROP 1 LAST LOCATION C8B6
J 0
(-1050 3350);
DISPLAY 0.617021 (-1050 3350);
PAINT AQUA (-1050 3350);
FORCEPROP 1 LASTPIN (-1100 3350) $PN 1
J 0
(-1090 3330);
DISPLAY 0.617021 (-1090 3330);
PAINT ORANGE (-1090 3330);
FORCEPROP 1 LAST PART_NUMBER C95333-007
J 0
(-1050 3100);
DISPLAY 0.617021 (-1050 3100);
PAINT BLUE (-1050 3100);
FORCEPROP 2 LAST CDS_LIB mstr_discrete
J 0
(-1100 3250);
PAINT ORANGE (-1100 3250);
DISPLAY INVISIBLE (-1100 3250);
FORCEPROP 2 LAST CDS_LOCATION C8B6
J 0
(-1050 3350);
DISPLAY 0.617021 (-1050 3350);
PAINT AQUA (-1050 3350);
DISPLAY INVISIBLE (-1050 3350);
FORCEPROP 1 LAST PATH I40
J 0
(-1050 3400);
DISPLAY 0.978723 (-1050 3400);
PAINT WHITE (-1050 3400);
DISPLAY INVISIBLE (-1050 3400);
FORCEPROP 2 LAST ROOM P5V_PWR_SWITCH
J 0
(-1050 3400);
DISPLAY 1.361702 (-1050 3400);
PAINT ORANGE (-1050 3400);
DISPLAY INVISIBLE (-1050 3400);
FORCEPROP 2 LAST SEC 1
J 0
(-1050 3450);
DISPLAY 0.680851 (-1050 3450);
PAINT MONO (-1050 3450);
DISPLAY INVISIBLE (-1050 3450);
FORCEPROP 2 LAST SEC_TYPE 0805
J 0
(-1050 3450);
DISPLAY 1.021277 (-1050 3450);
PAINT ORANGE (-1050 3450);
DISPLAY INVISIBLE (-1050 3450);
FORCEADD CAP_A..1
(-775 3250);
FORCEPROP 1 LAST PACK_TYPE 0402V
J 0
(-725 3050);
DISPLAY 0.617021 (-725 3050);
PAINT SKYBLUE (-725 3050);
FORCEPROP 1 LASTPIN (-775 3150) $PN 2
J 0
(-765 3130);
DISPLAY 0.617021 (-765 3130);
PAINT ORANGE (-765 3130);
FORCEPROP 1 LASTPIN (-775 3350) $PN 1
J 0
(-765 3330);
DISPLAY 0.617021 (-765 3330);
PAINT ORANGE (-765 3330);
FORCEPROP 1 LAST MATERIAL X7R
J 0
(-725 3150);
DISPLAY 0.617021 (-725 3150);
PAINT SKYBLUE (-725 3150);
FORCEPROP 1 LAST VOLTAGE 16V
J 0
(-725 3250);
DISPLAY 0.617021 (-725 3250);
PAINT SKYBLUE (-725 3250);
FORCEPROP 1 LAST TOLERANCE 10%
J 0
(-725 3200);
DISPLAY 0.617021 (-725 3200);
PAINT SKYBLUE (-725 3200);
FORCEPROP 1 LAST VALUE 0.1UF
J 0
(-725 3300);
DISPLAY 0.617021 (-725 3300);
PAINT SKYBLUE (-725 3300);
FORCEPROP 1 LAST PART_NUMBER A36096-030
J 0
(-725 3100);
DISPLAY 0.617021 (-725 3100);
PAINT BLUE (-725 3100);
FORCEPROP 1 LAST LOCATION C8B7
J 0
(-725 3350);
DISPLAY 0.617021 (-725 3350);
PAINT AQUA (-725 3350);
FORCEPROP 2 LAST CDS_LIB dev_discrete
J 0
(-775 3250);
PAINT ORANGE (-775 3250);
DISPLAY INVISIBLE (-775 3250);
FORCEPROP 1 LAST PATH I41
J 0
(-725 3400);
DISPLAY 0.978723 (-725 3400);
PAINT WHITE (-725 3400);
DISPLAY INVISIBLE (-725 3400);
FORCEPROP 0 LAST ROOM P5V_PWR_SWITCH
J 0
(-725 3450);
DISPLAY 1.021277 (-725 3450);
PAINT ORANGE (-725 3450);
DISPLAY INVISIBLE (-725 3450);
FORCEPROP 2 LAST CDS_LOCATION C8B7
J 0
(-725 3350);
DISPLAY 0.617021 (-725 3350);
PAINT AQUA (-725 3350);
DISPLAY INVISIBLE (-725 3350);
FORCEPROP 2 LAST CDS_SEC 1
J 0
(-725 3400);
PAINT ORANGE (-725 3400);
DISPLAY INVISIBLE (-725 3400);
FORCEPROP 2 LAST SEC_TYPE 0402V
J 0
(-725 3450);
DISPLAY 1.021277 (-725 3450);
PAINT ORANGE (-725 3450);
DISPLAY INVISIBLE (-725 3450);
FORCEPROP 2 LAST SEC 1
J 0
(-725 3450);
DISPLAY 0.680851 (-725 3450);
PAINT MONO (-725 3450);
DISPLAY INVISIBLE (-725 3450);
FORCEPROP 0 LAST BOM_COST PWR_SWITCH
J 0
(-725 3550);
DISPLAY 1.021277 (-725 3550);
PAINT ORANGE (-725 3550);
DISPLAY INVISIBLE (-725 3550);
FORCEADD GND..1
(-925 2900);
FORCEPROP 3 LASTPIN (-925 2950) SIG_NAME GND\g
J 0
(-915 2960);
DISPLAY 0.659574 (-915 2960);
PAINT MONO (-915 2960);
DISPLAY INVISIBLE (-915 2960);
FORCEPROP 2 LAST CDS_LIB mstr_symbols
J 0
(-925 2900);
PAINT ORANGE (-925 2900);
DISPLAY INVISIBLE (-925 2900);
FORCEPROP 1 LAST VOLTAGE 0.0V
J 0
(-970 2857);
DISPLAY 0.340426 (-970 2857);
PAINT SKYBLUE (-970 2857);
DISPLAY INVISIBLE (-970 2857);
FORCEPROP 1 LAST SIZE 1B
J 0
(-850 2850);
DISPLAY 1.170213 (-850 2850);
PAINT AQUA (-850 2850);
DISPLAY INVISIBLE (-850 2850);
FORCEPROP 1 LAST PATH I42
J 0
(-850 2900);
DISPLAY 0.872340 (-850 2900);
PAINT AQUA (-850 2900);
DISPLAY INVISIBLE (-850 2900);
FORCEPROP 1 LAST BODY_TYPE PLUMBING
J 0
(-970 2857);
DISPLAY 0.340426 (-970 2857);
PAINT GREEN (-970 2857);
DISPLAY INVISIBLE (-970 2857);
FORCEPROP 1 LAST HDL_POWER GND
J 0
(-925 3050);
DISPLAY 1.170213 (-925 3050);
PAINT GREEN (-925 3050);
DISPLAY INVISIBLE (-925 3050);
FORCEADD CAP_A..1
(-5050 4275);
FORCEPROP 1 LAST PACK_TYPE 0402V
J 0
(-5000 4075);
DISPLAY 0.617021 (-5000 4075);
PAINT SKYBLUE (-5000 4075);
FORCEPROP 1 LASTPIN (-5050 4175) $PN 2
J 0
(-5040 4155);
DISPLAY 0.617021 (-5040 4155);
PAINT ORANGE (-5040 4155);
FORCEPROP 1 LAST TOLERANCE 10%
J 0
(-5000 4225);
DISPLAY 0.617021 (-5000 4225);
PAINT SKYBLUE (-5000 4225);
FORCEPROP 1 LAST VOLTAGE 16V
J 0
(-5000 4275);
DISPLAY 0.617021 (-5000 4275);
PAINT SKYBLUE (-5000 4275);
FORCEPROP 1 LASTPIN (-5050 4375) $PN 1
J 0
(-5040 4355);
DISPLAY 0.617021 (-5040 4355);
PAINT ORANGE (-5040 4355);
FORCEPROP 1 LAST LOCATION C2T36
J 0
(-5000 4375);
DISPLAY 0.617021 (-5000 4375);
PAINT AQUA (-5000 4375);
FORCEPROP 1 LAST VALUE 0.1UF
J 0
(-5000 4325);
DISPLAY 0.617021 (-5000 4325);
PAINT SKYBLUE (-5000 4325);
FORCEPROP 1 LAST PART_NUMBER A36096-030
J 0
(-5000 4125);
DISPLAY 0.617021 (-5000 4125);
PAINT BLUE (-5000 4125);
FORCEPROP 1 LAST MATERIAL X7R
J 0
(-5000 4175);
DISPLAY 0.617021 (-5000 4175);
PAINT SKYBLUE (-5000 4175);
FORCEPROP 2 LAST CDS_LIB dev_discrete
J 0
(-5050 4275);
PAINT ORANGE (-5050 4275);
DISPLAY INVISIBLE (-5050 4275);
FORCEPROP 1 LAST PATH I43
J 0
(-5000 4425);
DISPLAY 0.978723 (-5000 4425);
PAINT WHITE (-5000 4425);
DISPLAY INVISIBLE (-5000 4425);
FORCEPROP 0 LAST ROOM P3V3_PWR_SWITCH
J 0
(-5000 4475);
DISPLAY 1.021277 (-5000 4475);
PAINT ORANGE (-5000 4475);
DISPLAY INVISIBLE (-5000 4475);
FORCEPROP 2 LAST CDS_LOCATION C2T36
J 0
(-5000 4375);
DISPLAY 0.617021 (-5000 4375);
PAINT AQUA (-5000 4375);
DISPLAY INVISIBLE (-5000 4375);
FORCEPROP 2 LAST CDS_SEC 1
J 0
(-5000 4425);
PAINT ORANGE (-5000 4425);
DISPLAY INVISIBLE (-5000 4425);
FORCEPROP 2 LAST SEC_TYPE 0402V
J 0
(-5000 4475);
DISPLAY 1.021277 (-5000 4475);
PAINT ORANGE (-5000 4475);
DISPLAY INVISIBLE (-5000 4475);
FORCEPROP 2 LAST SEC 1
J 0
(-5000 4475);
DISPLAY 0.680851 (-5000 4475);
PAINT MONO (-5000 4475);
DISPLAY INVISIBLE (-5000 4475);
FORCEPROP 0 LAST BOM_COST PWR_SWITCH
J 0
(-5000 4575);
DISPLAY 1.021277 (-5000 4575);
PAINT ORANGE (-5000 4575);
DISPLAY INVISIBLE (-5000 4575);
FORCEADD CAP..1
(-5375 4275);
FORCEPROP 1 LAST PACK_TYPE 0805
J 0
(-5325 4075);
DISPLAY 0.617021 (-5325 4075);
PAINT SKYBLUE (-5325 4075);
FORCEPROP 1 LASTPIN (-5375 4175) $PN 2
J 0
(-5365 4155);
DISPLAY 0.617021 (-5365 4155);
PAINT ORANGE (-5365 4155);
FORCEPROP 1 LAST VALUE 10UF
J 0
(-5325 4325);
DISPLAY 0.617021 (-5325 4325);
PAINT SKYBLUE (-5325 4325);
FORCEPROP 1 LAST VOLTAGE 16V
J 0
(-5325 4275);
DISPLAY 0.617021 (-5325 4275);
PAINT SKYBLUE (-5325 4275);
FORCEPROP 1 LAST LOCATION C2U1
J 0
(-5325 4375);
DISPLAY 0.617021 (-5325 4375);
PAINT AQUA (-5325 4375);
FORCEPROP 1 LASTPIN (-5375 4375) $PN 1
J 0
(-5365 4355);
DISPLAY 0.617021 (-5365 4355);
PAINT ORANGE (-5365 4355);
FORCEPROP 1 LAST PART_NUMBER C95333-007
J 0
(-5325 4125);
DISPLAY 0.617021 (-5325 4125);
PAINT BLUE (-5325 4125);
FORCEPROP 1 LAST MATERIAL X6S
J 0
(-5325 4175);
DISPLAY 0.617021 (-5325 4175);
PAINT SKYBLUE (-5325 4175);
FORCEPROP 1 LAST TOLERANCE 10%
J 0
(-5325 4225);
DISPLAY 0.617021 (-5325 4225);
PAINT SKYBLUE (-5325 4225);
FORCEPROP 2 LAST CDS_LIB mstr_discrete
J 0
(-5375 4275);
PAINT ORANGE (-5375 4275);
DISPLAY INVISIBLE (-5375 4275);
FORCEPROP 2 LAST SEC_TYPE 0805
J 0
(-5325 4475);
DISPLAY 1.021277 (-5325 4475);
PAINT ORANGE (-5325 4475);
DISPLAY INVISIBLE (-5325 4475);
FORCEPROP 2 LAST SEC 1
J 0
(-5325 4475);
DISPLAY 0.680851 (-5325 4475);
PAINT MONO (-5325 4475);
DISPLAY INVISIBLE (-5325 4475);
FORCEPROP 2 LAST CDS_LOCATION C2U1
J 0
(-5325 4375);
DISPLAY 0.617021 (-5325 4375);
PAINT AQUA (-5325 4375);
DISPLAY INVISIBLE (-5325 4375);
FORCEPROP 1 LAST PATH I44
J 0
(-5325 4425);
DISPLAY 0.978723 (-5325 4425);
PAINT WHITE (-5325 4425);
DISPLAY INVISIBLE (-5325 4425);
FORCEPROP 2 LAST ROOM P3V3_PWR_SWITCH
J 0
(-5325 4425);
DISPLAY 1.361702 (-5325 4425);
PAINT ORANGE (-5325 4425);
DISPLAY INVISIBLE (-5325 4425);
FORCEADD GND..1
(-5075 3925);
FORCEPROP 3 LASTPIN (-5075 3975) SIG_NAME GND\g
J 0
(-5065 3985);
DISPLAY 0.659574 (-5065 3985);
PAINT MONO (-5065 3985);
DISPLAY INVISIBLE (-5065 3985);
FORCEPROP 1 LAST VOLTAGE 0.0V
J 0
(-5120 3882);
DISPLAY 0.340426 (-5120 3882);
PAINT SKYBLUE (-5120 3882);
DISPLAY INVISIBLE (-5120 3882);
FORCEPROP 1 LAST PATH I45
J 0
(-5000 3925);
DISPLAY 0.872340 (-5000 3925);
PAINT AQUA (-5000 3925);
DISPLAY INVISIBLE (-5000 3925);
FORCEPROP 1 LAST SIZE 1B
J 0
(-5000 3875);
DISPLAY 1.170213 (-5000 3875);
PAINT AQUA (-5000 3875);
DISPLAY INVISIBLE (-5000 3875);
FORCEPROP 2 LAST CDS_LIB mstr_symbols
J 0
(-5075 3925);
PAINT ORANGE (-5075 3925);
DISPLAY INVISIBLE (-5075 3925);
FORCEPROP 1 LAST BODY_TYPE PLUMBING
J 0
(-5120 3882);
DISPLAY 0.340426 (-5120 3882);
PAINT GREEN (-5120 3882);
DISPLAY INVISIBLE (-5120 3882);
FORCEPROP 1 LAST HDL_POWER GND
J 0
(-5075 4075);
DISPLAY 1.170213 (-5075 4075);
PAINT GREEN (-5075 4075);
DISPLAY INVISIBLE (-5075 4075);
FORCEADD CAP_A..1
(-4675 3200);
FORCEPROP 1 LAST PACK_TYPE 0402V
J 0
(-4625 3000);
DISPLAY 0.617021 (-4625 3000);
PAINT SKYBLUE (-4625 3000);
FORCEPROP 1 LASTPIN (-4675 3100) $PN 2
J 0
(-4665 3080);
DISPLAY 0.617021 (-4665 3080);
PAINT ORANGE (-4665 3080);
FORCEPROP 1 LASTPIN (-4675 3300) $PN 1
J 0
(-4665 3280);
DISPLAY 0.617021 (-4665 3280);
PAINT ORANGE (-4665 3280);
FORCEPROP 1 LAST MATERIAL X7R
J 0
(-4625 3100);
DISPLAY 0.617021 (-4625 3100);
PAINT SKYBLUE (-4625 3100);
FORCEPROP 1 LAST VOLTAGE 16V
J 0
(-4625 3200);
DISPLAY 0.617021 (-4625 3200);
PAINT SKYBLUE (-4625 3200);
FORCEPROP 1 LAST TOLERANCE 10%
J 0
(-4625 3150);
DISPLAY 0.617021 (-4625 3150);
PAINT SKYBLUE (-4625 3150);
FORCEPROP 1 LAST VALUE 0.1UF
J 0
(-4625 3250);
DISPLAY 0.617021 (-4625 3250);
PAINT SKYBLUE (-4625 3250);
FORCEPROP 1 LAST LOCATION C2U19
J 0
(-4625 3300);
DISPLAY 0.617021 (-4625 3300);
PAINT AQUA (-4625 3300);
FORCEPROP 1 LAST PART_NUMBER A36096-030
J 0
(-4625 3050);
DISPLAY 0.617021 (-4625 3050);
PAINT BLUE (-4625 3050);
FORCEPROP 2 LAST CDS_LOCATION C2U19
J 0
(-4625 3300);
DISPLAY 0.617021 (-4625 3300);
PAINT AQUA (-4625 3300);
DISPLAY INVISIBLE (-4625 3300);
FORCEPROP 2 LAST CDS_LIB dev_discrete
J 0
(-4675 3200);
PAINT ORANGE (-4675 3200);
DISPLAY INVISIBLE (-4675 3200);
FORCEPROP 1 LAST PATH I46
J 0
(-4625 3350);
DISPLAY 0.978723 (-4625 3350);
PAINT WHITE (-4625 3350);
DISPLAY INVISIBLE (-4625 3350);
FORCEPROP 0 LAST ROOM P3V3_PWR_SWITCH
J 0
(-4625 3400);
DISPLAY 1.021277 (-4625 3400);
PAINT ORANGE (-4625 3400);
DISPLAY INVISIBLE (-4625 3400);
FORCEPROP 0 LAST BOM_COST PWR_SWITCH
J 0
(-4625 3500);
DISPLAY 1.021277 (-4625 3500);
PAINT ORANGE (-4625 3500);
DISPLAY INVISIBLE (-4625 3500);
FORCEPROP 2 LAST CDS_SEC 1
J 0
(-4625 3350);
PAINT ORANGE (-4625 3350);
DISPLAY INVISIBLE (-4625 3350);
FORCEPROP 2 LAST SEC_TYPE 0402V
J 0
(-4625 3400);
DISPLAY 1.021277 (-4625 3400);
PAINT ORANGE (-4625 3400);
DISPLAY INVISIBLE (-4625 3400);
FORCEPROP 2 LAST SEC 1
J 0
(-4625 3400);
DISPLAY 0.680851 (-4625 3400);
PAINT MONO (-4625 3400);
DISPLAY INVISIBLE (-4625 3400);
FORCEADD CAP..1
(-5000 3200);
FORCEPROP 1 LAST PACK_TYPE 0805
J 0
(-4950 3000);
DISPLAY 0.617021 (-4950 3000);
PAINT SKYBLUE (-4950 3000);
FORCEPROP 1 LASTPIN (-5000 3100) $PN 2
J 0
(-4990 3080);
DISPLAY 0.617021 (-4990 3080);
PAINT ORANGE (-4990 3080);
FORCEPROP 1 LASTPIN (-5000 3300) $PN 1
J 0
(-4990 3280);
DISPLAY 0.617021 (-4990 3280);
PAINT ORANGE (-4990 3280);
FORCEPROP 1 LAST MATERIAL X6S
J 0
(-4950 3100);
DISPLAY 0.617021 (-4950 3100);
PAINT SKYBLUE (-4950 3100);
FORCEPROP 1 LAST VOLTAGE 16V
J 0
(-4950 3200);
DISPLAY 0.617021 (-4950 3200);
PAINT SKYBLUE (-4950 3200);
FORCEPROP 1 LAST TOLERANCE 10%
J 0
(-4950 3150);
DISPLAY 0.617021 (-4950 3150);
PAINT SKYBLUE (-4950 3150);
FORCEPROP 1 LAST VALUE 10UF
J 0
(-4950 3250);
DISPLAY 0.617021 (-4950 3250);
PAINT SKYBLUE (-4950 3250);
FORCEPROP 1 LAST LOCATION C2U2
J 0
(-4950 3300);
DISPLAY 0.617021 (-4950 3300);
PAINT AQUA (-4950 3300);
FORCEPROP 1 LAST PART_NUMBER C95333-007
J 0
(-4950 3050);
DISPLAY 0.617021 (-4950 3050);
PAINT BLUE (-4950 3050);
FORCEPROP 2 LAST CDS_LIB mstr_discrete
J 0
(-5000 3200);
PAINT ORANGE (-5000 3200);
DISPLAY INVISIBLE (-5000 3200);
FORCEPROP 2 LAST CDS_LOCATION C2U2
J 0
(-4950 3300);
DISPLAY 0.617021 (-4950 3300);
PAINT AQUA (-4950 3300);
DISPLAY INVISIBLE (-4950 3300);
FORCEPROP 2 LAST SEC_TYPE 0805
J 0
(-4950 3400);
DISPLAY 1.021277 (-4950 3400);
PAINT ORANGE (-4950 3400);
DISPLAY INVISIBLE (-4950 3400);
FORCEPROP 2 LAST SEC 1
J 0
(-4950 3400);
DISPLAY 0.680851 (-4950 3400);
PAINT MONO (-4950 3400);
DISPLAY INVISIBLE (-4950 3400);
FORCEPROP 1 LAST PATH I47
J 0
(-4950 3350);
DISPLAY 0.978723 (-4950 3350);
PAINT WHITE (-4950 3350);
DISPLAY INVISIBLE (-4950 3350);
FORCEPROP 2 LAST ROOM P3V3_PWR_SWITCH
J 0
(-4950 3350);
DISPLAY 1.361702 (-4950 3350);
PAINT ORANGE (-4950 3350);
DISPLAY INVISIBLE (-4950 3350);
FORCEADD GND..1
(-4775 2850);
FORCEPROP 3 LASTPIN (-4775 2900) SIG_NAME GND\g
J 0
(-4765 2910);
DISPLAY 0.659574 (-4765 2910);
PAINT MONO (-4765 2910);
DISPLAY INVISIBLE (-4765 2910);
FORCEPROP 1 LAST SIZE 1B
J 0
(-4700 2800);
DISPLAY 1.170213 (-4700 2800);
PAINT AQUA (-4700 2800);
DISPLAY INVISIBLE (-4700 2800);
FORCEPROP 1 LAST VOLTAGE 0.0V
J 0
(-4820 2807);
DISPLAY 0.340426 (-4820 2807);
PAINT SKYBLUE (-4820 2807);
DISPLAY INVISIBLE (-4820 2807);
FORCEPROP 2 LAST CDS_LIB mstr_symbols
J 0
(-4775 2850);
PAINT ORANGE (-4775 2850);
DISPLAY INVISIBLE (-4775 2850);
FORCEPROP 1 LAST PATH I48
J 0
(-4700 2850);
DISPLAY 0.872340 (-4700 2850);
PAINT AQUA (-4700 2850);
DISPLAY INVISIBLE (-4700 2850);
FORCEPROP 1 LAST BODY_TYPE PLUMBING
J 0
(-4820 2807);
DISPLAY 0.340426 (-4820 2807);
PAINT GREEN (-4820 2807);
DISPLAY INVISIBLE (-4820 2807);
FORCEPROP 1 LAST HDL_POWER GND
J 0
(-4775 3000);
DISPLAY 1.170213 (-4775 3000);
PAINT GREEN (-4775 3000);
DISPLAY INVISIBLE (-4775 3000);
FORCEADD CAP_A..1
(-4675 1200);
FORCEPROP 1 LAST PACK_TYPE 0402V
J 0
(-4625 1000);
DISPLAY 0.617021 (-4625 1000);
PAINT SKYBLUE (-4625 1000);
FORCEPROP 1 LASTPIN (-4675 1100) $PN 2
J 0
(-4665 1080);
DISPLAY 0.617021 (-4665 1080);
PAINT ORANGE (-4665 1080);
FORCEPROP 1 LASTPIN (-4675 1300) $PN 1
J 0
(-4665 1280);
DISPLAY 0.617021 (-4665 1280);
PAINT ORANGE (-4665 1280);
FORCEPROP 1 LAST MATERIAL X7R
J 0
(-4625 1100);
DISPLAY 0.617021 (-4625 1100);
PAINT SKYBLUE (-4625 1100);
FORCEPROP 1 LAST VOLTAGE 16V
J 0
(-4625 1200);
DISPLAY 0.617021 (-4625 1200);
PAINT SKYBLUE (-4625 1200);
FORCEPROP 1 LAST TOLERANCE 10%
J 0
(-4625 1150);
DISPLAY 0.617021 (-4625 1150);
PAINT SKYBLUE (-4625 1150);
FORCEPROP 1 LAST VALUE 0.1UF
J 0
(-4625 1250);
DISPLAY 0.617021 (-4625 1250);
PAINT SKYBLUE (-4625 1250);
FORCEPROP 1 LAST PART_NUMBER A36096-030
J 0
(-4625 1050);
DISPLAY 0.617021 (-4625 1050);
PAINT BLUE (-4625 1050);
FORCEPROP 1 LAST LOCATION C7E9
J 0
(-4625 1300);
DISPLAY 0.617021 (-4625 1300);
PAINT AQUA (-4625 1300);
FORCEPROP 2 LAST CDS_LIB dev_discrete
J 0
(-4675 1200);
PAINT ORANGE (-4675 1200);
DISPLAY INVISIBLE (-4675 1200);
FORCEPROP 1 LAST PATH I49
J 0
(-4625 1350);
DISPLAY 0.978723 (-4625 1350);
PAINT WHITE (-4625 1350);
DISPLAY INVISIBLE (-4625 1350);
FORCEPROP 2 LAST CDS_LOCATION C7E9
J 0
(-4625 1300);
DISPLAY 0.617021 (-4625 1300);
PAINT AQUA (-4625 1300);
DISPLAY INVISIBLE (-4625 1300);
FORCEPROP 2 LAST CDS_SEC 1
J 0
(-4625 1350);
PAINT ORANGE (-4625 1350);
DISPLAY INVISIBLE (-4625 1350);
FORCEPROP 0 LAST ROOM P12V_PWR_SWITCH
J 0
(-4625 1400);
DISPLAY 1.021277 (-4625 1400);
PAINT ORANGE (-4625 1400);
DISPLAY INVISIBLE (-4625 1400);
FORCEPROP 2 LAST SEC_TYPE 0402V
J 0
(-4625 1400);
DISPLAY 1.021277 (-4625 1400);
PAINT ORANGE (-4625 1400);
DISPLAY INVISIBLE (-4625 1400);
FORCEPROP 2 LAST SEC 1
J 0
(-4625 1400);
DISPLAY 0.680851 (-4625 1400);
PAINT MONO (-4625 1400);
DISPLAY INVISIBLE (-4625 1400);
FORCEPROP 0 LAST BOM_COST PWR_SWITCH
J 0
(-4625 1500);
DISPLAY 1.021277 (-4625 1500);
PAINT ORANGE (-4625 1500);
DISPLAY INVISIBLE (-4625 1500);
FORCEADD CAP..1
(-5125 1250);
FORCEPROP 1 LASTPIN (-5125 1150) $PN 2
J 0
(-5115 1130);
DISPLAY 0.617021 (-5115 1130);
PAINT ORANGE (-5115 1130);
FORCEPROP 1 LAST MATERIAL X6S
J 0
(-5075 1150);
DISPLAY 0.617021 (-5075 1150);
PAINT SKYBLUE (-5075 1150);
FORCEPROP 1 LAST VOLTAGE 16V
J 0
(-5075 1250);
DISPLAY 0.617021 (-5075 1250);
PAINT SKYBLUE (-5075 1250);
FORCEPROP 1 LAST PACK_TYPE 0805
J 0
(-5075 1050);
DISPLAY 0.617021 (-5075 1050);
PAINT SKYBLUE (-5075 1050);
FORCEPROP 1 LAST TOLERANCE 10%
J 0
(-5075 1200);
DISPLAY 0.617021 (-5075 1200);
PAINT SKYBLUE (-5075 1200);
FORCEPROP 1 LAST VALUE 10UF
J 0
(-5075 1300);
DISPLAY 0.617021 (-5075 1300);
PAINT SKYBLUE (-5075 1300);
FORCEPROP 1 LASTPIN (-5125 1350) $PN 1
J 0
(-5115 1330);
DISPLAY 0.617021 (-5115 1330);
PAINT ORANGE (-5115 1330);
FORCEPROP 1 LAST LOCATION C7E8
J 0
(-5075 1350);
DISPLAY 0.617021 (-5075 1350);
PAINT AQUA (-5075 1350);
FORCEPROP 1 LAST PART_NUMBER C95333-007
J 0
(-5075 1100);
DISPLAY 0.617021 (-5075 1100);
PAINT BLUE (-5075 1100);
FORCEPROP 2 LAST CDS_LIB mstr_discrete
J 0
(-5125 1250);
PAINT ORANGE (-5125 1250);
DISPLAY INVISIBLE (-5125 1250);
FORCEPROP 2 LAST SEC_TYPE 0805
J 0
(-5075 1450);
DISPLAY 1.021277 (-5075 1450);
PAINT ORANGE (-5075 1450);
DISPLAY INVISIBLE (-5075 1450);
FORCEPROP 2 LAST SEC 1
J 0
(-5075 1450);
DISPLAY 0.680851 (-5075 1450);
PAINT MONO (-5075 1450);
DISPLAY INVISIBLE (-5075 1450);
FORCEPROP 2 LAST CDS_LOCATION C7E8
J 0
(-5075 1350);
DISPLAY 0.617021 (-5075 1350);
PAINT AQUA (-5075 1350);
DISPLAY INVISIBLE (-5075 1350);
FORCEPROP 1 LAST PATH I50
J 0
(-5075 1400);
DISPLAY 0.978723 (-5075 1400);
PAINT WHITE (-5075 1400);
DISPLAY INVISIBLE (-5075 1400);
FORCEPROP 2 LAST ROOM P12V_PWR_SWITCH
J 0
(-5075 1400);
DISPLAY 1.361702 (-5075 1400);
PAINT ORANGE (-5075 1400);
DISPLAY INVISIBLE (-5075 1400);
FORCEADD GND..1
(-5125 925);
FORCEPROP 3 LASTPIN (-5125 975) SIG_NAME GND\g
J 0
(-5115 985);
DISPLAY 0.659574 (-5115 985);
PAINT MONO (-5115 985);
DISPLAY INVISIBLE (-5115 985);
FORCEPROP 2 LAST CDS_LIB mstr_symbols
J 0
(-5125 925);
PAINT ORANGE (-5125 925);
DISPLAY INVISIBLE (-5125 925);
FORCEPROP 1 LAST VOLTAGE 0.0V
J 0
(-5170 882);
DISPLAY 0.340426 (-5170 882);
PAINT SKYBLUE (-5170 882);
DISPLAY INVISIBLE (-5170 882);
FORCEPROP 1 LAST PATH I51
J 0
(-5050 925);
DISPLAY 0.872340 (-5050 925);
PAINT AQUA (-5050 925);
DISPLAY INVISIBLE (-5050 925);
FORCEPROP 1 LAST SIZE 1B
J 0
(-5050 875);
DISPLAY 1.170213 (-5050 875);
PAINT AQUA (-5050 875);
DISPLAY INVISIBLE (-5050 875);
FORCEPROP 1 LAST BODY_TYPE PLUMBING
J 0
(-5170 882);
DISPLAY 0.340426 (-5170 882);
PAINT GREEN (-5170 882);
DISPLAY INVISIBLE (-5170 882);
FORCEPROP 1 LAST HDL_POWER GND
J 0
(-5125 1075);
DISPLAY 1.170213 (-5125 1075);
PAINT GREEN (-5125 1075);
DISPLAY INVISIBLE (-5125 1075);
FORCEADD CAP_A..1
(-4775 2250);
FORCEPROP 1 LASTPIN (-4775 2150) $PN 2
J 0
(-4765 2130);
DISPLAY 0.617021 (-4765 2130);
PAINT ORANGE (-4765 2130);
FORCEPROP 1 LAST MATERIAL X7R
J 0
(-4725 2150);
DISPLAY 0.617021 (-4725 2150);
PAINT SKYBLUE (-4725 2150);
FORCEPROP 1 LAST VOLTAGE 16V
J 0
(-4725 2250);
DISPLAY 0.617021 (-4725 2250);
PAINT SKYBLUE (-4725 2250);
FORCEPROP 1 LAST TOLERANCE 10%
J 0
(-4725 2200);
DISPLAY 0.617021 (-4725 2200);
PAINT SKYBLUE (-4725 2200);
FORCEPROP 1 LASTPIN (-4775 2350) $PN 1
J 0
(-4765 2330);
DISPLAY 0.617021 (-4765 2330);
PAINT ORANGE (-4765 2330);
FORCEPROP 1 LAST LOCATION C7E5
J 0
(-4725 2350);
DISPLAY 0.617021 (-4725 2350);
PAINT AQUA (-4725 2350);
FORCEPROP 1 LAST PACK_TYPE 0402V
J 0
(-4725 2050);
DISPLAY 0.617021 (-4725 2050);
PAINT SKYBLUE (-4725 2050);
FORCEPROP 1 LAST VALUE 0.1UF
J 0
(-4725 2300);
DISPLAY 0.617021 (-4725 2300);
PAINT SKYBLUE (-4725 2300);
FORCEPROP 1 LAST PART_NUMBER A36096-030
J 0
(-4725 2100);
DISPLAY 0.617021 (-4725 2100);
PAINT BLUE (-4725 2100);
FORCEPROP 2 LAST CDS_LIB dev_discrete
J 0
(-4775 2250);
PAINT ORANGE (-4775 2250);
DISPLAY INVISIBLE (-4775 2250);
FORCEPROP 0 LAST ROOM P12V_PWR_SWITCH
J 0
(-4725 2450);
DISPLAY 1.021277 (-4725 2450);
PAINT ORANGE (-4725 2450);
DISPLAY INVISIBLE (-4725 2450);
FORCEPROP 1 LAST PATH I52
J 0
(-4725 2400);
DISPLAY 0.978723 (-4725 2400);
PAINT WHITE (-4725 2400);
DISPLAY INVISIBLE (-4725 2400);
FORCEPROP 2 LAST CDS_LOCATION C7E5
J 0
(-4725 2350);
DISPLAY 0.617021 (-4725 2350);
PAINT AQUA (-4725 2350);
DISPLAY INVISIBLE (-4725 2350);
FORCEPROP 2 LAST CDS_SEC 1
J 0
(-4725 2400);
PAINT ORANGE (-4725 2400);
DISPLAY INVISIBLE (-4725 2400);
FORCEPROP 2 LAST SEC_TYPE 0402V
J 0
(-4725 2450);
DISPLAY 1.021277 (-4725 2450);
PAINT ORANGE (-4725 2450);
DISPLAY INVISIBLE (-4725 2450);
FORCEPROP 2 LAST SEC 1
J 0
(-4725 2450);
DISPLAY 0.680851 (-4725 2450);
PAINT MONO (-4725 2450);
DISPLAY INVISIBLE (-4725 2450);
FORCEPROP 0 LAST BOM_COST PWR_SWITCH
J 0
(-4725 2550);
DISPLAY 1.021277 (-4725 2550);
PAINT ORANGE (-4725 2550);
DISPLAY INVISIBLE (-4725 2550);
FORCEADD CAP..1
(-5100 2250);
FORCEPROP 1 LASTPIN (-5100 2150) $PN 2
J 0
(-5090 2130);
DISPLAY 0.617021 (-5090 2130);
PAINT ORANGE (-5090 2130);
FORCEPROP 1 LAST MATERIAL X6S
J 0
(-5050 2150);
DISPLAY 0.617021 (-5050 2150);
PAINT SKYBLUE (-5050 2150);
FORCEPROP 1 LAST VOLTAGE 16V
J 0
(-5050 2250);
DISPLAY 0.617021 (-5050 2250);
PAINT SKYBLUE (-5050 2250);
FORCEPROP 1 LAST TOLERANCE 10%
J 0
(-5050 2200);
DISPLAY 0.617021 (-5050 2200);
PAINT SKYBLUE (-5050 2200);
FORCEPROP 1 LAST PACK_TYPE 0805
J 0
(-5050 2050);
DISPLAY 0.617021 (-5050 2050);
PAINT SKYBLUE (-5050 2050);
FORCEPROP 1 LAST VALUE 10UF
J 0
(-5050 2300);
DISPLAY 0.617021 (-5050 2300);
PAINT SKYBLUE (-5050 2300);
FORCEPROP 1 LASTPIN (-5100 2350) $PN 1
J 0
(-5090 2330);
DISPLAY 0.617021 (-5090 2330);
PAINT ORANGE (-5090 2330);
FORCEPROP 1 LAST LOCATION C7E6
J 0
(-5050 2350);
DISPLAY 0.617021 (-5050 2350);
PAINT AQUA (-5050 2350);
FORCEPROP 1 LAST PART_NUMBER C95333-007
J 0
(-5050 2100);
DISPLAY 0.617021 (-5050 2100);
PAINT BLUE (-5050 2100);
FORCEPROP 2 LAST CDS_LIB mstr_discrete
J 0
(-5100 2250);
PAINT ORANGE (-5100 2250);
DISPLAY INVISIBLE (-5100 2250);
FORCEPROP 2 LAST ROOM P12V_PWR_SWITCH
J 0
(-5050 2400);
DISPLAY 1.361702 (-5050 2400);
PAINT ORANGE (-5050 2400);
DISPLAY INVISIBLE (-5050 2400);
FORCEPROP 1 LAST PATH I53
J 0
(-5050 2400);
DISPLAY 0.978723 (-5050 2400);
PAINT WHITE (-5050 2400);
DISPLAY INVISIBLE (-5050 2400);
FORCEPROP 2 LAST CDS_LOCATION C7E6
J 0
(-5050 2350);
DISPLAY 0.617021 (-5050 2350);
PAINT AQUA (-5050 2350);
DISPLAY INVISIBLE (-5050 2350);
FORCEPROP 2 LAST SEC 1
J 0
(-5050 2450);
DISPLAY 0.680851 (-5050 2450);
PAINT MONO (-5050 2450);
DISPLAY INVISIBLE (-5050 2450);
FORCEPROP 2 LAST SEC_TYPE 0805
J 0
(-5050 2450);
DISPLAY 1.021277 (-5050 2450);
PAINT ORANGE (-5050 2450);
DISPLAY INVISIBLE (-5050 2450);
FORCEADD GND..1
(-4800 1900);
FORCEPROP 3 LASTPIN (-4800 1950) SIG_NAME GND\g
J 0
(-4790 1960);
DISPLAY 0.659574 (-4790 1960);
PAINT MONO (-4790 1960);
DISPLAY INVISIBLE (-4790 1960);
FORCEPROP 1 LAST VOLTAGE 0.0V
J 0
(-4845 1857);
DISPLAY 0.340426 (-4845 1857);
PAINT SKYBLUE (-4845 1857);
DISPLAY INVISIBLE (-4845 1857);
FORCEPROP 2 LAST CDS_LIB mstr_symbols
J 0
(-4800 1900);
PAINT ORANGE (-4800 1900);
DISPLAY INVISIBLE (-4800 1900);
FORCEPROP 1 LAST SIZE 1B
J 0
(-4725 1850);
DISPLAY 1.170213 (-4725 1850);
PAINT AQUA (-4725 1850);
DISPLAY INVISIBLE (-4725 1850);
FORCEPROP 1 LAST PATH I54
J 0
(-4725 1900);
DISPLAY 0.872340 (-4725 1900);
PAINT AQUA (-4725 1900);
DISPLAY INVISIBLE (-4725 1900);
FORCEPROP 1 LAST BODY_TYPE PLUMBING
J 0
(-4845 1857);
DISPLAY 0.340426 (-4845 1857);
PAINT GREEN (-4845 1857);
DISPLAY INVISIBLE (-4845 1857);
FORCEPROP 1 LAST HDL_POWER GND
J 0
(-4800 2050);
DISPLAY 1.170213 (-4800 2050);
PAINT GREEN (-4800 2050);
DISPLAY INVISIBLE (-4800 2050);
FORCEADD OFFPAGE..1
(-7925 3875);
FORCEPROP 2 LAST $XR0 191 
J 0
(-8207 3875);
DISPLAY 0.638298 (-8207 3875);
PAINT MONO (-8207 3875);
FORCEPROP 2 LAST PATH I58
J 0
(-7875 3950);
DISPLAY 1.021277 (-7875 3950);
PAINT ORANGE (-7875 3950);
DISPLAY INVISIBLE (-7875 3950);
FORCEPROP 2 LAST CDS_LIB mstr_standard
J 0
(-7925 3875);
PAINT ORANGE (-7925 3875);
DISPLAY INVISIBLE (-7925 3875);
FORCEPROP 1 LAST OFFPAGE TRUE
J 0
(-7600 3750);
DISPLAY 1.170213 (-7600 3750);
PAINT GREEN (-7600 3750);
DISPLAY INVISIBLE (-7600 3750);
FORCEPROP 1 LAST COMMENT_BODY TRUE
J 0
(-7800 3775);
DISPLAY 1.170213 (-7800 3775);
PAINT PEACH (-7800 3775);
DISPLAY INVISIBLE (-7800 3775);
FORCEADD OFFPAGE..1
(-7925 1900);
FORCEPROP 2 LAST $XR0 191 
J 0
(-8207 1900);
DISPLAY 0.638298 (-8207 1900);
PAINT MONO (-8207 1900);
FORCEPROP 2 LAST PATH I59
J 0
(-7875 1975);
DISPLAY 1.021277 (-7875 1975);
PAINT ORANGE (-7875 1975);
DISPLAY INVISIBLE (-7875 1975);
FORCEPROP 2 LAST CDS_LIB mstr_standard
J 0
(-7925 1900);
PAINT ORANGE (-7925 1900);
DISPLAY INVISIBLE (-7925 1900);
FORCEPROP 1 LAST OFFPAGE TRUE
J 0
(-7600 1775);
DISPLAY 1.170213 (-7600 1775);
PAINT GREEN (-7600 1775);
DISPLAY INVISIBLE (-7600 1775);
FORCEPROP 1 LAST COMMENT_BODY TRUE
J 0
(-7800 1800);
DISPLAY 1.170213 (-7800 1800);
PAINT PEACH (-7800 1800);
DISPLAY INVISIBLE (-7800 1800);
FORCEADD P3V3_STBY..1
(-5600 4600);
FORCEPROP 3 LASTPIN (-5600 4550) SIG_NAME P3V3_STBY\g
J 0
(-5590 4560);
DISPLAY 0.659574 (-5590 4560);
PAINT MONO (-5590 4560);
DISPLAY INVISIBLE (-5590 4560);
FORCEPROP 1 LAST VOLTAGE 3.3V
J 0
(-5645 4557);
DISPLAY 0.340426 (-5645 4557);
PAINT SKYBLUE (-5645 4557);
DISPLAY INVISIBLE (-5645 4557);
FORCEPROP 1 LAST PATH I6
J 0
(-5555 4602);
DISPLAY 0.340426 (-5555 4602);
PAINT GREEN (-5555 4602);
DISPLAY INVISIBLE (-5555 4602);
FORCEPROP 2 LAST CDS_LIB mstr_symbols
J 0
(-5600 4600);
PAINT ORANGE (-5600 4600);
DISPLAY INVISIBLE (-5600 4600);
FORCEPROP 1 LAST SIZE 1B
J 0
(-5555 4622);
DISPLAY 0.340426 (-5555 4622);
PAINT GREEN (-5555 4622);
DISPLAY INVISIBLE (-5555 4622);
FORCEPROP 1 LAST BODY_TYPE PLUMBING
J 0
(-5645 4557);
DISPLAY 0.340426 (-5645 4557);
PAINT GREEN (-5645 4557);
DISPLAY INVISIBLE (-5645 4557);
FORCEPROP 1 LAST HDL_POWER P3V3_STBY
J 0
(-5900 4475);
DISPLAY 0.872340 (-5900 4475);
PAINT ORANGE (-5900 4475);
DISPLAY INVISIBLE (-5900 4475);
FORCEADD CAP..1
(-1175 1225);
FORCEPROP 1 LASTPIN (-1175 1125) $PN 2
J 0
(-1165 1105);
DISPLAY 0.617021 (-1165 1105);
PAINT ORANGE (-1165 1105);
FORCEPROP 1 LAST MATERIAL X6S
J 0
(-1125 1125);
DISPLAY 0.617021 (-1125 1125);
PAINT SKYBLUE (-1125 1125);
FORCEPROP 1 LAST VOLTAGE 16V
J 0
(-1125 1225);
DISPLAY 0.617021 (-1125 1225);
PAINT SKYBLUE (-1125 1225);
FORCEPROP 1 LAST TOLERANCE 10%
J 0
(-1125 1175);
DISPLAY 0.617021 (-1125 1175);
PAINT SKYBLUE (-1125 1175);
FORCEPROP 1 LASTPIN (-1175 1325) $PN 1
J 0
(-1165 1305);
DISPLAY 0.617021 (-1165 1305);
PAINT ORANGE (-1165 1305);
FORCEPROP 1 LAST PACK_TYPE 0805
J 0
(-1125 1025);
DISPLAY 0.617021 (-1125 1025);
PAINT SKYBLUE (-1125 1025);
FORCEPROP 1 LAST VALUE 10UF
J 0
(-1125 1275);
DISPLAY 0.617021 (-1125 1275);
PAINT SKYBLUE (-1125 1275);
FORCEPROP 1 LAST PART_NUMBER C95333-007
J 0
(-1125 1075);
DISPLAY 0.617021 (-1125 1075);
PAINT BLUE (-1125 1075);
FORCEPROP 1 LAST LOCATION C1B18
J 0
(-1125 1325);
DISPLAY 0.617021 (-1125 1325);
PAINT AQUA (-1125 1325);
FORCEPROP 2 LAST CDS_LIB mstr_discrete
J 0
(-1175 1225);
PAINT ORANGE (-1175 1225);
DISPLAY INVISIBLE (-1175 1225);
FORCEPROP 2 LAST ROOM P12V_FAN_PWR_SWITCH
J 0
(-1125 1375);
DISPLAY 1.361702 (-1125 1375);
PAINT ORANGE (-1125 1375);
DISPLAY INVISIBLE (-1125 1375);
FORCEPROP 1 LAST PATH I61
J 0
(-1125 1375);
DISPLAY 0.978723 (-1125 1375);
PAINT WHITE (-1125 1375);
DISPLAY INVISIBLE (-1125 1375);
FORCEPROP 2 LAST CDS_LOCATION C1B18
J 0
(-1125 1325);
DISPLAY 0.617021 (-1125 1325);
PAINT AQUA (-1125 1325);
DISPLAY INVISIBLE (-1125 1325);
FORCEPROP 2 LAST SEC 1
J 0
(-1125 1425);
DISPLAY 0.680851 (-1125 1425);
PAINT MONO (-1125 1425);
DISPLAY INVISIBLE (-1125 1425);
FORCEPROP 2 LAST SEC_TYPE 0805
J 0
(-1125 1425);
DISPLAY 1.021277 (-1125 1425);
PAINT ORANGE (-1125 1425);
DISPLAY INVISIBLE (-1125 1425);
FORCEADD GND..1
(-1175 900);
FORCEPROP 3 LASTPIN (-1175 950) SIG_NAME GND\g
J 0
(-1165 960);
DISPLAY 0.659574 (-1165 960);
PAINT MONO (-1165 960);
DISPLAY INVISIBLE (-1165 960);
FORCEPROP 1 LAST VOLTAGE 0.0V
J 0
(-1220 857);
DISPLAY 0.340426 (-1220 857);
PAINT SKYBLUE (-1220 857);
DISPLAY INVISIBLE (-1220 857);
FORCEPROP 2 LAST CDS_LIB mstr_symbols
J 0
(-1175 900);
PAINT ORANGE (-1175 900);
DISPLAY INVISIBLE (-1175 900);
FORCEPROP 1 LAST SIZE 1B
J 0
(-1100 850);
DISPLAY 1.170213 (-1100 850);
PAINT AQUA (-1100 850);
DISPLAY INVISIBLE (-1100 850);
FORCEPROP 1 LAST PATH I63
J 0
(-1100 900);
DISPLAY 0.872340 (-1100 900);
PAINT AQUA (-1100 900);
DISPLAY INVISIBLE (-1100 900);
FORCEPROP 1 LAST BODY_TYPE PLUMBING
J 0
(-1220 857);
DISPLAY 0.340426 (-1220 857);
PAINT GREEN (-1220 857);
DISPLAY INVISIBLE (-1220 857);
FORCEPROP 1 LAST HDL_POWER GND
J 0
(-1175 1050);
DISPLAY 1.170213 (-1175 1050);
PAINT GREEN (-1175 1050);
DISPLAY INVISIBLE (-1175 1050);
FORCEADD CAP_A..1
(-725 1225);
FORCEPROP 1 LASTPIN (-725 1125) $PN 2
J 0
(-715 1105);
DISPLAY 0.617021 (-715 1105);
PAINT ORANGE (-715 1105);
FORCEPROP 1 LAST MATERIAL X7R
J 0
(-675 1125);
DISPLAY 0.617021 (-675 1125);
PAINT SKYBLUE (-675 1125);
FORCEPROP 1 LAST VOLTAGE 16V
J 0
(-675 1225);
DISPLAY 0.617021 (-675 1225);
PAINT SKYBLUE (-675 1225);
FORCEPROP 1 LAST PACK_TYPE 0402V
J 0
(-675 1025);
DISPLAY 0.617021 (-675 1025);
PAINT SKYBLUE (-675 1025);
FORCEPROP 1 LAST TOLERANCE 10%
J 0
(-675 1175);
DISPLAY 0.617021 (-675 1175);
PAINT SKYBLUE (-675 1175);
FORCEPROP 1 LAST VALUE 0.1UF
J 0
(-675 1275);
DISPLAY 0.617021 (-675 1275);
PAINT SKYBLUE (-675 1275);
FORCEPROP 1 LASTPIN (-725 1325) $PN 1
J 0
(-715 1305);
DISPLAY 0.617021 (-715 1305);
PAINT ORANGE (-715 1305);
FORCEPROP 1 LAST LOCATION C1B19
J 0
(-675 1325);
DISPLAY 0.617021 (-675 1325);
PAINT AQUA (-675 1325);
FORCEPROP 1 LAST PART_NUMBER A36096-030
J 0
(-675 1075);
DISPLAY 0.617021 (-675 1075);
PAINT BLUE (-675 1075);
FORCEPROP 2 LAST CDS_LIB dev_discrete
J 0
(-725 1225);
PAINT ORANGE (-725 1225);
DISPLAY INVISIBLE (-725 1225);
FORCEPROP 2 LAST CDS_LOCATION C1B19
J 0
(-675 1325);
DISPLAY 0.617021 (-675 1325);
PAINT AQUA (-675 1325);
DISPLAY INVISIBLE (-675 1325);
FORCEPROP 2 LAST CDS_SEC 1
J 0
(-675 1375);
PAINT ORANGE (-675 1375);
DISPLAY INVISIBLE (-675 1375);
FORCEPROP 1 LAST PATH I64
J 0
(-675 1375);
DISPLAY 0.978723 (-675 1375);
PAINT WHITE (-675 1375);
DISPLAY INVISIBLE (-675 1375);
FORCEPROP 2 LAST SEC 1
J 0
(-675 1425);
DISPLAY 0.680851 (-675 1425);
PAINT MONO (-675 1425);
DISPLAY INVISIBLE (-675 1425);
FORCEPROP 2 LAST SEC_TYPE 0402V
J 0
(-675 1425);
DISPLAY 1.021277 (-675 1425);
PAINT ORANGE (-675 1425);
DISPLAY INVISIBLE (-675 1425);
FORCEPROP 0 LAST ROOM P12V_FAN_PWR_SWITCH
J 0
(-675 1425);
DISPLAY 1.021277 (-675 1425);
PAINT ORANGE (-675 1425);
DISPLAY INVISIBLE (-675 1425);
FORCEPROP 0 LAST BOM_COST PWR_SWITCH
J 0
(-675 1525);
DISPLAY 1.021277 (-675 1525);
PAINT ORANGE (-675 1525);
DISPLAY INVISIBLE (-675 1525);
FORCEADD OFFPAGE..1
(-3975 1875);
FORCEPROP 2 LAST $XR1 181 
J 0
(-4347 1875);
DISPLAY 0.638298 (-4347 1875);
PAINT MONO (-4347 1875);
FORCEPROP 2 LAST $XR0 161 
J 0
(-4227 1875);
DISPLAY 0.638298 (-4227 1875);
PAINT MONO (-4227 1875);
FORCEPROP 2 LAST PATH I65
J 0
(-3925 1950);
DISPLAY 1.021277 (-3925 1950);
PAINT ORANGE (-3925 1950);
DISPLAY INVISIBLE (-3925 1950);
FORCEPROP 2 LAST CDS_LIB mstr_standard
J 0
(-3975 1875);
PAINT ORANGE (-3975 1875);
DISPLAY INVISIBLE (-3975 1875);
FORCEPROP 1 LAST OFFPAGE TRUE
J 0
(-3650 1750);
DISPLAY 1.170213 (-3650 1750);
PAINT GREEN (-3650 1750);
DISPLAY INVISIBLE (-3650 1750);
FORCEPROP 1 LAST COMMENT_BODY TRUE
J 0
(-3850 1775);
DISPLAY 1.170213 (-3850 1775);
PAINT PEACH (-3850 1775);
DISPLAY INVISIBLE (-3850 1775);
FORCEADD GND..1
(-3775 1950);
FORCEPROP 3 LASTPIN (-3775 2000) SIG_NAME GND\g
J 0
(-3765 2010);
DISPLAY 0.659574 (-3765 2010);
PAINT MONO (-3765 2010);
DISPLAY INVISIBLE (-3765 2010);
FORCEPROP 1 LAST PATH I66
J 0
(-3700 1950);
DISPLAY 0.872340 (-3700 1950);
PAINT AQUA (-3700 1950);
DISPLAY INVISIBLE (-3700 1950);
FORCEPROP 2 LAST CDS_LIB mstr_symbols
J 0
(-3775 1950);
PAINT ORANGE (-3775 1950);
DISPLAY INVISIBLE (-3775 1950);
FORCEPROP 1 LAST SIZE 1B
J 0
(-3700 1900);
DISPLAY 1.170213 (-3700 1900);
PAINT AQUA (-3700 1900);
DISPLAY INVISIBLE (-3700 1900);
FORCEPROP 1 LAST VOLTAGE 0.0V
J 0
(-3820 1907);
DISPLAY 0.340426 (-3820 1907);
PAINT SKYBLUE (-3820 1907);
DISPLAY INVISIBLE (-3820 1907);
FORCEPROP 1 LAST BODY_TYPE PLUMBING
J 0
(-3820 1907);
DISPLAY 0.340426 (-3820 1907);
PAINT GREEN (-3820 1907);
DISPLAY INVISIBLE (-3820 1907);
FORCEPROP 1 LAST HDL_POWER GND
J 0
(-3775 2100);
DISPLAY 1.170213 (-3775 2100);
PAINT GREEN (-3775 2100);
DISPLAY INVISIBLE (-3775 2100);
FORCEADD CAP_A..1
(-3775 2150);
FORCEPROP 1 LAST PACK_TYPE 0402V
J 0
(-3725 1950);
DISPLAY 0.617021 (-3725 1950);
PAINT SKYBLUE (-3725 1950);
FORCEPROP 1 LAST PART_NUMBER A36096-030
J 0
(-3725 2000);
DISPLAY 0.617021 (-3725 2000);
PAINT BLUE (-3725 2000);
FORCEPROP 1 LASTPIN (-3775 2050) $PN 2
J 0
(-3765 2030);
DISPLAY 0.617021 (-3765 2030);
PAINT ORANGE (-3765 2030);
FORCEPROP 1 LASTPIN (-3775 2250) $PN 1
J 0
(-3765 2230);
DISPLAY 0.617021 (-3765 2230);
PAINT ORANGE (-3765 2230);
FORCEPROP 1 LAST TOLERANCE 10%
J 0
(-3725 2100);
DISPLAY 0.617021 (-3725 2100);
PAINT SKYBLUE (-3725 2100);
FORCEPROP 1 LAST VOLTAGE 16V
J 0
(-3725 2150);
DISPLAY 0.617021 (-3725 2150);
PAINT SKYBLUE (-3725 2150);
FORCEPROP 1 LAST MATERIAL X7R
J 0
(-3725 2050);
DISPLAY 0.617021 (-3725 2050);
PAINT SKYBLUE (-3725 2050);
FORCEPROP 1 LAST VALUE 0.1UF
J 0
(-3725 2200);
DISPLAY 0.617021 (-3725 2200);
PAINT SKYBLUE (-3725 2200);
FORCEPROP 1 LAST LOCATION C9M6
J 0
(-3725 2250);
DISPLAY 0.617021 (-3725 2250);
PAINT AQUA (-3725 2250);
FORCEPROP 2 LAST CDS_LOCATION C9M6
J 0
(-3725 2250);
DISPLAY 0.617021 (-3725 2250);
PAINT AQUA (-3725 2250);
DISPLAY INVISIBLE (-3725 2250);
FORCEPROP 2 LAST CDS_LIB dev_discrete
J 0
(-3775 2150);
PAINT ORANGE (-3775 2150);
DISPLAY INVISIBLE (-3775 2150);
FORCEPROP 1 LAST PATH I67
J 0
(-3725 2300);
DISPLAY 0.978723 (-3725 2300);
PAINT WHITE (-3725 2300);
DISPLAY INVISIBLE (-3725 2300);
FORCEPROP 2 LAST CDS_SEC 1
J 0
(-3725 2300);
PAINT ORANGE (-3725 2300);
DISPLAY INVISIBLE (-3725 2300);
FORCEPROP 0 LAST ROOM P12V_FAN_PWR_SWITCH
J 0
(-3725 2350);
DISPLAY 1.021277 (-3725 2350);
PAINT ORANGE (-3725 2350);
DISPLAY INVISIBLE (-3725 2350);
FORCEPROP 2 LAST SEC_TYPE 0402V
J 0
(-3725 2350);
DISPLAY 1.021277 (-3725 2350);
PAINT ORANGE (-3725 2350);
DISPLAY INVISIBLE (-3725 2350);
FORCEPROP 2 LAST SEC 1
J 0
(-3725 2350);
DISPLAY 0.680851 (-3725 2350);
PAINT MONO (-3725 2350);
DISPLAY INVISIBLE (-3725 2350);
FORCEADD P5V_STBY..1
(-3425 2500);
FORCEPROP 3 LASTPIN (-3425 2450) SIG_NAME P5V_STBY\g
J 0
(-3415 2460);
DISPLAY 0.659574 (-3415 2460);
PAINT MONO (-3415 2460);
DISPLAY INVISIBLE (-3415 2460);
FORCEPROP 1 LAST VOLTAGE 5.0V
J 0
(-3470 2457);
DISPLAY 0.340426 (-3470 2457);
PAINT SKYBLUE (-3470 2457);
DISPLAY INVISIBLE (-3470 2457);
FORCEPROP 2 LAST CDS_LIB mstr_symbols
J 0
(-3425 2500);
PAINT ORANGE (-3425 2500);
DISPLAY INVISIBLE (-3425 2500);
FORCEPROP 1 LAST SIZE 1B
J 0
(-3380 2522);
DISPLAY 0.340426 (-3380 2522);
PAINT GREEN (-3380 2522);
DISPLAY INVISIBLE (-3380 2522);
FORCEPROP 1 LAST PATH I68
J 0
(-3380 2502);
DISPLAY 0.340426 (-3380 2502);
PAINT GREEN (-3380 2502);
DISPLAY INVISIBLE (-3380 2502);
FORCEPROP 1 LAST BODY_TYPE PLUMBING
J 0
(-3470 2457);
DISPLAY 0.340426 (-3470 2457);
PAINT GREEN (-3470 2457);
DISPLAY INVISIBLE (-3470 2457);
FORCEPROP 1 LAST HDL_POWER P5V_STBY
J 0
(-3725 2375);
DISPLAY 0.872340 (-3725 2375);
PAINT ORANGE (-3725 2375);
DISPLAY INVISIBLE (-3725 2375);
FORCEADD SLG55021..1
(-2775 1825);
FORCEPROP 2 LASTPIN (-3075 1775) $PN 3
J 2
(-3085 1785);
DISPLAY 0.617021 (-3085 1785);
PAINT ORANGE (-3085 1785);
FORCEPROP 2 LASTPIN (-3075 1975) $PN 1
J 2
(-3085 1985);
DISPLAY 0.617021 (-3085 1985);
PAINT ORANGE (-3085 1985);
FORCEPROP 2 LASTPIN (-3075 1875) $PN 2
J 2
(-3085 1885);
DISPLAY 0.617021 (-3085 1885);
PAINT ORANGE (-3085 1885);
FORCEPROP 1 LAST PART_NUMBER G56246-001
J 0
(-3025 1525);
DISPLAY 0.617021 (-3025 1525);
PAINT BLUE (-3025 1525);
FORCEPROP 2 LASTPIN (-2475 1675) $PN 4
J 0
(-2465 1685);
DISPLAY 0.617021 (-2465 1685);
PAINT ORANGE (-2465 1685);
FORCEPROP 2 LASTPIN (-2475 1625) $PN 9
J 0
(-2465 1635);
DISPLAY 0.617021 (-2465 1635);
PAINT ORANGE (-2465 1635);
FORCEPROP 2 LASTPIN (-2475 1775) $PN 6
J 0
(-2465 1785);
DISPLAY 0.617021 (-2465 1785);
PAINT ORANGE (-2465 1785);
FORCEPROP 2 LASTPIN (-2475 1975) $PN 8
J 0
(-2465 1985);
DISPLAY 0.617021 (-2465 1985);
PAINT ORANGE (-2465 1985);
FORCEPROP 2 LASTPIN (-2475 1825) $PN 7
J 0
(-2465 1835);
DISPLAY 0.617021 (-2465 1835);
PAINT ORANGE (-2465 1835);
FORCEPROP 2 LASTPIN (-2475 1875) $PN 5
J 0
(-2465 1885);
DISPLAY 0.617021 (-2465 1885);
PAINT ORANGE (-2465 1885);
FORCEPROP 1 LAST MATERIAL IC
J 0
(-3025 2125);
DISPLAY 0.617021 (-3025 2125);
PAINT SKYBLUE (-3025 2125);
FORCEPROP 1 LAST LOCATION EU9M1
J 0
(-3025 2175);
DISPLAY 0.617021 (-3025 2175);
PAINT AQUA (-3025 2175);
FORCEPROP 2 LAST CDS_LIB mstr_vreg
J 0
(-2775 1825);
PAINT ORANGE (-2775 1825);
DISPLAY INVISIBLE (-2775 1825);
FORCEPROP 1 LAST CDS_LMAN_SYM_OUTLINE -250,250,250,-250
J 0
(-2775 1825);
DISPLAY 0.468085 (-2775 1825);
PAINT GREEN (-2775 1825);
DISPLAY INVISIBLE (-2775 1825);
FORCEPROP 0 LAST ROOM P12V_FAN_PWR_SWITCH
J 0
(-3025 2275);
DISPLAY 1.021277 (-3025 2275);
PAINT ORANGE (-3025 2275);
DISPLAY INVISIBLE (-3025 2275);
FORCEPROP 1 LAST PATH I69
J 0
(-2775 2125);
PAINT GREEN (-2775 2125);
DISPLAY INVISIBLE (-2775 2125);
FORCEPROP 2 LAST CDS_LOCATION EU9M1
J 0
(-3025 2175);
DISPLAY 0.617021 (-3025 2175);
PAINT AQUA (-3025 2175);
DISPLAY INVISIBLE (-3025 2175);
FORCEPROP 2 LAST SEC 1
J 0
(-3025 2225);
DISPLAY 0.680851 (-3025 2225);
PAINT MONO (-3025 2225);
DISPLAY INVISIBLE (-3025 2225);
FORCEPROP 2 LAST SEC_TYPE SM
J 0
(-3025 2225);
DISPLAY 1.021277 (-3025 2225);
PAINT ORANGE (-3025 2225);
DISPLAY INVISIBLE (-3025 2225);
FORCEPROP 1 LAST PACK_TYPE SM
J 0
(-3025 2225);
PAINT SKYBLUE (-3025 2225);
DISPLAY INVISIBLE (-3025 2225);
FORCEADD P3V3..1
(-5125 3675);
FORCEPROP 3 LASTPIN (-5125 3625) SIG_NAME P3V3\g
J 0
(-5115 3635);
DISPLAY 0.659574 (-5115 3635);
PAINT MONO (-5115 3635);
DISPLAY INVISIBLE (-5115 3635);
FORCEPROP 2 LAST CDS_LIB mstr_symbols
J 0
(-5125 3675);
PAINT ORANGE (-5125 3675);
DISPLAY INVISIBLE (-5125 3675);
FORCEPROP 1 LAST PATH I7
J 0
(-5080 3677);
DISPLAY 0.340426 (-5080 3677);
PAINT GREEN (-5080 3677);
DISPLAY INVISIBLE (-5080 3677);
FORCEPROP 1 LAST SIZE 1B
J 0
(-5080 3697);
DISPLAY 0.340426 (-5080 3697);
PAINT GREEN (-5080 3697);
DISPLAY INVISIBLE (-5080 3697);
FORCEPROP 1 LAST VOLTAGE +3.3V
J 0
(-5025 3825);
DISPLAY 1.021277 (-5025 3825);
PAINT SKYBLUE (-5025 3825);
DISPLAY INVISIBLE (-5025 3825);
FORCEPROP 1 LAST BODY_TYPE PLUMBING
J 0
(-5170 3632);
DISPLAY 0.340426 (-5170 3632);
PAINT GREEN (-5170 3632);
DISPLAY INVISIBLE (-5170 3632);
FORCEPROP 1 LAST HDL_POWER P3V3
J 0
(-5450 3550);
DISPLAY 0.872340 (-5450 3550);
PAINT ORANGE (-5450 3550);
DISPLAY INVISIBLE (-5450 3550);
FORCEADD GND..1
(-2250 1450);
FORCEPROP 3 LASTPIN (-2250 1500) SIG_NAME GND\g
J 0
(-2240 1510);
DISPLAY 0.659574 (-2240 1510);
PAINT MONO (-2240 1510);
DISPLAY INVISIBLE (-2240 1510);
FORCEPROP 1 LAST PATH I70
J 0
(-2175 1450);
DISPLAY 0.872340 (-2175 1450);
PAINT AQUA (-2175 1450);
DISPLAY INVISIBLE (-2175 1450);
FORCEPROP 2 LAST CDS_LIB mstr_symbols
J 0
(-2250 1450);
PAINT ORANGE (-2250 1450);
DISPLAY INVISIBLE (-2250 1450);
FORCEPROP 1 LAST SIZE 1B
J 0
(-2175 1400);
DISPLAY 1.170213 (-2175 1400);
PAINT AQUA (-2175 1400);
DISPLAY INVISIBLE (-2175 1400);
FORCEPROP 1 LAST VOLTAGE 0.0V
J 0
(-2295 1407);
DISPLAY 0.340426 (-2295 1407);
PAINT SKYBLUE (-2295 1407);
DISPLAY INVISIBLE (-2295 1407);
FORCEPROP 1 LAST BODY_TYPE PLUMBING
J 0
(-2295 1407);
DISPLAY 0.340426 (-2295 1407);
PAINT GREEN (-2295 1407);
DISPLAY INVISIBLE (-2295 1407);
FORCEPROP 1 LAST HDL_POWER GND
J 0
(-2250 1600);
DISPLAY 1.170213 (-2250 1600);
PAINT GREEN (-2250 1600);
DISPLAY INVISIBLE (-2250 1600);
FORCEADD P12V_STBY..1
(-1375 2550);
FORCEPROP 3 LASTPIN (-1375 2500) SIG_NAME P12V_STBY\g
J 0
(-1365 2510);
DISPLAY 0.659574 (-1365 2510);
PAINT MONO (-1365 2510);
DISPLAY INVISIBLE (-1365 2510);
FORCEPROP 1 LAST VOLTAGE 12.0V
J 0
(-1420 2507);
DISPLAY 0.340426 (-1420 2507);
PAINT SKYBLUE (-1420 2507);
DISPLAY INVISIBLE (-1420 2507);
FORCEPROP 1 LAST PATH I73
J 0
(-1330 2552);
DISPLAY 0.340426 (-1330 2552);
PAINT GREEN (-1330 2552);
DISPLAY INVISIBLE (-1330 2552);
FORCEPROP 2 LAST CDS_LIB mstr_symbols
J 0
(-1375 2550);
PAINT ORANGE (-1375 2550);
DISPLAY INVISIBLE (-1375 2550);
FORCEPROP 1 LAST SIZE 1B
J 0
(-1330 2572);
DISPLAY 0.340426 (-1330 2572);
PAINT GREEN (-1330 2572);
DISPLAY INVISIBLE (-1330 2572);
FORCEPROP 1 LAST BODY_TYPE PLUMBING
J 0
(-1420 2507);
DISPLAY 0.340426 (-1420 2507);
PAINT GREEN (-1420 2507);
DISPLAY INVISIBLE (-1420 2507);
FORCEPROP 1 LAST HDL_POWER P12V_STBY
J 0
(-1675 2425);
DISPLAY 0.872340 (-1675 2425);
PAINT ORANGE (-1675 2425);
DISPLAY INVISIBLE (-1675 2425);
FORCEADD CAP..1
(-1150 2225);
FORCEPROP 1 LASTPIN (-1150 2325) $PN 1
J 0
(-1140 2305);
DISPLAY 0.617021 (-1140 2305);
PAINT ORANGE (-1140 2305);
FORCEPROP 1 LAST VOLTAGE 16V
J 0
(-1100 2225);
DISPLAY 0.617021 (-1100 2225);
PAINT SKYBLUE (-1100 2225);
FORCEPROP 1 LAST TOLERANCE 10%
J 0
(-1100 2175);
DISPLAY 0.617021 (-1100 2175);
PAINT SKYBLUE (-1100 2175);
FORCEPROP 1 LAST VALUE 10UF
J 0
(-1100 2275);
DISPLAY 0.617021 (-1100 2275);
PAINT SKYBLUE (-1100 2275);
FORCEPROP 1 LAST PACK_TYPE 0805
J 0
(-1100 2025);
DISPLAY 0.617021 (-1100 2025);
PAINT SKYBLUE (-1100 2025);
FORCEPROP 1 LAST LOCATION C9M10
J 0
(-1100 2325);
DISPLAY 0.617021 (-1100 2325);
PAINT AQUA (-1100 2325);
FORCEPROP 1 LASTPIN (-1150 2125) $PN 2
J 0
(-1140 2105);
DISPLAY 0.617021 (-1140 2105);
PAINT ORANGE (-1140 2105);
FORCEPROP 1 LAST MATERIAL X6S
J 0
(-1100 2125);
DISPLAY 0.617021 (-1100 2125);
PAINT SKYBLUE (-1100 2125);
FORCEPROP 1 LAST PART_NUMBER C95333-007
J 0
(-1100 2075);
DISPLAY 0.617021 (-1100 2075);
PAINT BLUE (-1100 2075);
FORCEPROP 2 LAST CDS_LIB mstr_discrete
J 0
(-1150 2225);
PAINT ORANGE (-1150 2225);
DISPLAY INVISIBLE (-1150 2225);
FORCEPROP 2 LAST SEC_TYPE 0805
J 0
(-1100 2425);
DISPLAY 1.021277 (-1100 2425);
PAINT ORANGE (-1100 2425);
DISPLAY INVISIBLE (-1100 2425);
FORCEPROP 2 LAST SEC 1
J 0
(-1100 2425);
DISPLAY 0.680851 (-1100 2425);
PAINT MONO (-1100 2425);
DISPLAY INVISIBLE (-1100 2425);
FORCEPROP 2 LAST CDS_LOCATION C9M10
J 0
(-1100 2325);
DISPLAY 0.617021 (-1100 2325);
PAINT AQUA (-1100 2325);
DISPLAY INVISIBLE (-1100 2325);
FORCEPROP 1 LAST PATH I74
J 0
(-1100 2375);
DISPLAY 0.978723 (-1100 2375);
PAINT WHITE (-1100 2375);
DISPLAY INVISIBLE (-1100 2375);
FORCEPROP 2 LAST ROOM P12V_FAN_PWR_SWITCH
J 0
(-1100 2375);
DISPLAY 1.361702 (-1100 2375);
PAINT ORANGE (-1100 2375);
DISPLAY INVISIBLE (-1100 2375);
FORCEADD GND..1
(-850 1900);
FORCEPROP 3 LASTPIN (-850 1950) SIG_NAME GND\g
J 0
(-840 1960);
DISPLAY 0.659574 (-840 1960);
PAINT MONO (-840 1960);
DISPLAY INVISIBLE (-840 1960);
FORCEPROP 1 LAST VOLTAGE 0.0V
J 0
(-895 1857);
DISPLAY 0.340426 (-895 1857);
PAINT SKYBLUE (-895 1857);
DISPLAY INVISIBLE (-895 1857);
FORCEPROP 2 LAST CDS_LIB mstr_symbols
J 0
(-850 1900);
PAINT ORANGE (-850 1900);
DISPLAY INVISIBLE (-850 1900);
FORCEPROP 1 LAST SIZE 1B
J 0
(-775 1850);
DISPLAY 1.170213 (-775 1850);
PAINT AQUA (-775 1850);
DISPLAY INVISIBLE (-775 1850);
FORCEPROP 1 LAST PATH I75
J 0
(-775 1900);
DISPLAY 0.872340 (-775 1900);
PAINT AQUA (-775 1900);
DISPLAY INVISIBLE (-775 1900);
FORCEPROP 1 LAST BODY_TYPE PLUMBING
J 0
(-895 1857);
DISPLAY 0.340426 (-895 1857);
PAINT GREEN (-895 1857);
DISPLAY INVISIBLE (-895 1857);
FORCEPROP 1 LAST HDL_POWER GND
J 0
(-850 2050);
DISPLAY 1.170213 (-850 2050);
PAINT GREEN (-850 2050);
DISPLAY INVISIBLE (-850 2050);
FORCEADD CAP_A..1
(-825 2225);
FORCEPROP 1 LAST PACK_TYPE 0402V
J 0
(-775 2025);
DISPLAY 0.617021 (-775 2025);
PAINT SKYBLUE (-775 2025);
FORCEPROP 1 LASTPIN (-825 2125) $PN 2
J 0
(-815 2105);
DISPLAY 0.617021 (-815 2105);
PAINT ORANGE (-815 2105);
FORCEPROP 1 LASTPIN (-825 2325) $PN 1
J 0
(-815 2305);
DISPLAY 0.617021 (-815 2305);
PAINT ORANGE (-815 2305);
FORCEPROP 1 LAST LOCATION C9M9
J 0
(-775 2325);
DISPLAY 0.617021 (-775 2325);
PAINT AQUA (-775 2325);
FORCEPROP 1 LAST PART_NUMBER A36096-030
J 0
(-775 2075);
DISPLAY 0.617021 (-775 2075);
PAINT BLUE (-775 2075);
FORCEPROP 1 LAST MATERIAL X7R
J 0
(-775 2125);
DISPLAY 0.617021 (-775 2125);
PAINT SKYBLUE (-775 2125);
FORCEPROP 1 LAST TOLERANCE 10%
J 0
(-775 2175);
DISPLAY 0.617021 (-775 2175);
PAINT SKYBLUE (-775 2175);
FORCEPROP 1 LAST VOLTAGE 16V
J 0
(-775 2225);
DISPLAY 0.617021 (-775 2225);
PAINT SKYBLUE (-775 2225);
FORCEPROP 1 LAST VALUE 0.1UF
J 0
(-775 2275);
DISPLAY 0.617021 (-775 2275);
PAINT SKYBLUE (-775 2275);
FORCEPROP 2 LAST CDS_LIB dev_discrete
J 0
(-825 2225);
PAINT ORANGE (-825 2225);
DISPLAY INVISIBLE (-825 2225);
FORCEPROP 2 LAST SEC 1
J 0
(-775 2425);
DISPLAY 0.680851 (-775 2425);
PAINT MONO (-775 2425);
DISPLAY INVISIBLE (-775 2425);
FORCEPROP 2 LAST SEC_TYPE 0402V
J 0
(-775 2425);
DISPLAY 1.021277 (-775 2425);
PAINT ORANGE (-775 2425);
DISPLAY INVISIBLE (-775 2425);
FORCEPROP 2 LAST CDS_SEC 1
J 0
(-775 2375);
PAINT ORANGE (-775 2375);
DISPLAY INVISIBLE (-775 2375);
FORCEPROP 2 LAST CDS_LOCATION C9M9
J 0
(-775 2325);
DISPLAY 0.617021 (-775 2325);
PAINT AQUA (-775 2325);
DISPLAY INVISIBLE (-775 2325);
FORCEPROP 1 LAST PATH I76
J 0
(-775 2375);
DISPLAY 0.978723 (-775 2375);
PAINT WHITE (-775 2375);
DISPLAY INVISIBLE (-775 2375);
FORCEPROP 0 LAST ROOM P12V_FAN_PWR_SWITCH
J 0
(-775 2425);
DISPLAY 1.021277 (-775 2425);
PAINT ORANGE (-775 2425);
DISPLAY INVISIBLE (-775 2425);
FORCEPROP 0 LAST BOM_COST PWR_SWITCH
J 0
(-775 2525);
DISPLAY 1.021277 (-775 2525);
PAINT ORANGE (-775 2525);
DISPLAY INVISIBLE (-775 2525);
FORCEADD P12V_FAN..1
(-725 1600);
FORCEPROP 3 LASTPIN (-725 1550) SIG_NAME P12V_FAN\g
J 0
(-715 1560);
DISPLAY 0.659574 (-715 1560);
PAINT MONO (-715 1560);
DISPLAY INVISIBLE (-715 1560);
FORCEPROP 1 LAST VOLTAGE 12.0V
J 0
(-770 1557);
DISPLAY 0.340426 (-770 1557);
PAINT SKYBLUE (-770 1557);
DISPLAY INVISIBLE (-770 1557);
FORCEPROP 2 LAST CDS_LIB mstr_symbols
J 0
(-725 1600);
PAINT ORANGE (-725 1600);
DISPLAY INVISIBLE (-725 1600);
FORCEPROP 1 LAST PATH I77
J 0
(-675 1625);
DISPLAY 0.872340 (-675 1625);
PAINT AQUA (-675 1625);
DISPLAY INVISIBLE (-675 1625);
FORCEPROP 1 LAST BODY_TYPE PLUMBING
J 0
(-770 1557);
DISPLAY 0.340426 (-770 1557);
PAINT GREEN (-770 1557);
DISPLAY INVISIBLE (-770 1557);
FORCEPROP 1 LAST HDL_POWER P12V_FAN
J 1
(-725 1650);
DISPLAY 0.872340 (-725 1650);
PAINT GREEN (-725 1650);
DISPLAY INVISIBLE (-725 1650);
FORCEADD RES..2
(-6925 3050);
FORCEPROP 1 LAST WATTAGE 1/16W
J 0
(-6885 3025);
DISPLAY 0.617021 (-6885 3025);
PAINT SKYBLUE (-6885 3025);
FORCEPROP 1 LAST MATERIAL EMPTY
J 0
(-6885 2975);
DISPLAY 0.617021 (-6885 2975);
PAINT RED (-6885 2975);
FORCEPROP 1 LAST PART_NUMBER G21796-072
J 0
(-6885 2925);
DISPLAY 0.617021 (-6885 2925);
PAINT BLUE (-6885 2925);
FORCEPROP 1 LAST TOLERANCE 1%
J 0
(-6880 3075);
DISPLAY 0.617021 (-6880 3075);
PAINT SKYBLUE (-6880 3075);
FORCEPROP 1 LAST LOCATION R8E12
J 0
(-6880 3175);
DISPLAY 0.617021 (-6880 3175);
PAINT AQUA (-6880 3175);
FORCEPROP 1 LAST VALUE 4.75K
J 0
(-6880 3125);
DISPLAY 0.617021 (-6880 3125);
PAINT SKYBLUE (-6880 3125);
FORCEPROP 1 LASTPIN (-6925 3150) $PN 1
J 0
(-6920 3112);
DISPLAY 0.787234 (-6920 3112);
PAINT ORANGE (-6920 3112);
FORCEPROP 1 LASTPIN (-6925 2950) $PN 2
J 0
(-6920 2960);
DISPLAY 0.787234 (-6920 2960);
PAINT ORANGE (-6920 2960);
FORCEPROP 1 LAST PACK_TYPE 0402
J 0
(-6885 2875);
DISPLAY 0.617021 (-6885 2875);
PAINT SKYBLUE (-6885 2875);
FORCEPROP 2 LAST CDS_LIB mstr_discrete
J 0
(-6925 3050);
PAINT MONO (-6925 3050);
DISPLAY INVISIBLE (-6925 3050);
FORCEPROP 0 LAST ROOM IO_SLOT
J 0
(-6875 3275);
DISPLAY 1.021277 (-6875 3275);
PAINT ORANGE (-6875 3275);
DISPLAY INVISIBLE (-6875 3275);
FORCEPROP 2 LAST CDS_LOCATION R8E12
J 0
(-6880 3175);
DISPLAY 0.617021 (-6880 3175);
PAINT AQUA (-6880 3175);
DISPLAY INVISIBLE (-6880 3175);
FORCEPROP 1 LAST PATH I78
J 0
(-6875 3225);
DISPLAY 0.978723 (-6875 3225);
PAINT WHITE (-6875 3225);
DISPLAY INVISIBLE (-6875 3225);
FORCEPROP 0 LAST BOM_COST IO_SLOT
J 0
(-6875 3375);
DISPLAY 1.021277 (-6875 3375);
PAINT ORANGE (-6875 3375);
DISPLAY INVISIBLE (-6875 3375);
FORCEPROP 2 LAST SEC 1
J 0
(-6875 3275);
PAINT MONO (-6875 3275);
DISPLAY INVISIBLE (-6875 3275);
FORCEPROP 2 LAST SEC_TYPE 0402
J 0
(-6875 3275);
DISPLAY 1.021277 (-6875 3275);
PAINT ORANGE (-6875 3275);
DISPLAY INVISIBLE (-6875 3275);
FORCEADD P3V3_STBY..1
(-6925 3275);
FORCEPROP 3 LASTPIN (-6925 3225) SIG_NAME P3V3_STBY\g
J 0
(-6915 3235);
DISPLAY 0.659574 (-6915 3235);
PAINT MONO (-6915 3235);
DISPLAY INVISIBLE (-6915 3235);
FORCEPROP 2 LAST CDS_LIB mstr_symbols
J 0
(-6925 3275);
PAINT MONO (-6925 3275);
DISPLAY INVISIBLE (-6925 3275);
FORCEPROP 1 LAST VOLTAGE 3.3V
J 0
(-6970 3232);
DISPLAY 0.340426 (-6970 3232);
PAINT SKYBLUE (-6970 3232);
DISPLAY INVISIBLE (-6970 3232);
FORCEPROP 1 LAST PATH I79
J 0
(-6880 3277);
DISPLAY 0.340426 (-6880 3277);
PAINT GREEN (-6880 3277);
DISPLAY INVISIBLE (-6880 3277);
FORCEPROP 1 LAST SIZE 1B
J 0
(-6880 3297);
DISPLAY 0.340426 (-6880 3297);
PAINT GREEN (-6880 3297);
DISPLAY INVISIBLE (-6880 3297);
FORCEPROP 1 LAST BODY_TYPE PLUMBING
J 0
(-6970 3232);
DISPLAY 0.340426 (-6970 3232);
PAINT GREEN (-6970 3232);
DISPLAY INVISIBLE (-6970 3232);
FORCEPROP 1 LAST HDL_POWER P3V3_STBY
J 0
(-7225 3150);
DISPLAY 0.872340 (-7225 3150);
PAINT ORANGE (-7225 3150);
DISPLAY INVISIBLE (-7225 3150);
FORCEADD RES..2
(-6850 2625);
FORCEPROP 1 LAST MATERIAL CHIP
J 0
(-6810 2550);
DISPLAY 0.617021 (-6810 2550);
PAINT SKYBLUE (-6810 2550);
FORCEPROP 1 LASTPIN (-6850 2725) $PN 1
J 0
(-6845 2687);
DISPLAY 0.617021 (-6845 2687);
PAINT ORANGE (-6845 2687);
FORCEPROP 1 LAST LOCATION R8B4
J 0
(-6805 2750);
DISPLAY 0.617021 (-6805 2750);
PAINT AQUA (-6805 2750);
FORCEPROP 1 LAST TOLERANCE 1%
J 0
(-6805 2650);
DISPLAY 0.617021 (-6805 2650);
PAINT SKYBLUE (-6805 2650);
FORCEPROP 1 LAST WATTAGE 1/16W
J 0
(-6810 2600);
DISPLAY 0.617021 (-6810 2600);
PAINT SKYBLUE (-6810 2600);
FORCEPROP 1 LAST VALUE 100.0K
J 0
(-6805 2700);
DISPLAY 0.617021 (-6805 2700);
PAINT SKYBLUE (-6805 2700);
FORCEPROP 1 LAST PACK_TYPE 0402
J 0
(-6810 2450);
DISPLAY 0.617021 (-6810 2450);
PAINT SKYBLUE (-6810 2450);
FORCEPROP 1 LASTPIN (-6850 2525) $PN 2
J 0
(-6845 2535);
DISPLAY 0.617021 (-6845 2535);
PAINT ORANGE (-6845 2535);
FORCEPROP 1 LAST PART_NUMBER G21796-010
J 0
(-6810 2500);
DISPLAY 0.617021 (-6810 2500);
PAINT BLUE (-6810 2500);
FORCEPROP 2 LAST CDS_LIB mstr_discrete
J 0
(-6850 2625);
PAINT ORANGE (-6850 2625);
DISPLAY INVISIBLE (-6850 2625);
FORCEPROP 2 LAST CDS_LOCATION R8B4
J 0
(-6805 2750);
DISPLAY 0.617021 (-6805 2750);
PAINT AQUA (-6805 2750);
DISPLAY INVISIBLE (-6805 2750);
FORCEPROP 2 LAST ROOM HOT_SWAP
J 0
(-6800 2800);
PAINT MONO (-6800 2800);
DISPLAY INVISIBLE (-6800 2800);
FORCEPROP 1 LAST PATH I83
J 0
(-6800 2800);
DISPLAY 0.978723 (-6800 2800);
PAINT WHITE (-6800 2800);
DISPLAY INVISIBLE (-6800 2800);
FORCEPROP 2 LAST SEC_TYPE 0402
J 0
(-6800 2850);
DISPLAY 1.021277 (-6800 2850);
PAINT ORANGE (-6800 2850);
DISPLAY INVISIBLE (-6800 2850);
FORCEPROP 2 LAST SEC 1
J 0
(-6800 2850);
DISPLAY 0.680851 (-6800 2850);
PAINT MONO (-6800 2850);
DISPLAY INVISIBLE (-6800 2850);
FORCEADD GND..1
(-6850 2425);
FORCEPROP 3 LASTPIN (-6850 2475) SIG_NAME GND\g
J 0
(-6840 2485);
DISPLAY 0.659574 (-6840 2485);
PAINT MONO (-6840 2485);
DISPLAY INVISIBLE (-6840 2485);
FORCEPROP 1 LAST VOLTAGE 0.0V
J 0
(-6895 2382);
DISPLAY 0.340426 (-6895 2382);
PAINT SKYBLUE (-6895 2382);
DISPLAY INVISIBLE (-6895 2382);
FORCEPROP 2 LAST CDS_LIB mstr_symbols
J 0
(-6850 2425);
PAINT ORANGE (-6850 2425);
DISPLAY INVISIBLE (-6850 2425);
FORCEPROP 1 LAST SIZE 1B
J 0
(-6775 2375);
DISPLAY 1.170213 (-6775 2375);
PAINT AQUA (-6775 2375);
DISPLAY INVISIBLE (-6775 2375);
FORCEPROP 1 LAST PATH I84
J 0
(-6775 2425);
DISPLAY 0.872340 (-6775 2425);
PAINT AQUA (-6775 2425);
DISPLAY INVISIBLE (-6775 2425);
FORCEPROP 1 LAST BODY_TYPE PLUMBING
J 0
(-6895 2382);
DISPLAY 0.340426 (-6895 2382);
PAINT GREEN (-6895 2382);
DISPLAY INVISIBLE (-6895 2382);
FORCEPROP 1 LAST HDL_POWER GND
J 0
(-6850 2575);
DISPLAY 1.170213 (-6850 2575);
PAINT GREEN (-6850 2575);
DISPLAY INVISIBLE (-6850 2575);
FORCEADD MOSFET_N..3
R 2
(-5650 3900);
FORCEPROP 1 LASTPIN (-5650 3700) $PN 1
J 2
(-5662 3695);
DISPLAY 0.617021 (-5662 3695);
PAINT WHITE (-5662 3695);
FORCEPROP 1 LASTPIN (-5850 4000) $PN 4
J 2
(-5847 4015);
DISPLAY 0.617021 (-5847 4015);
PAINT WHITE (-5847 4015);
FORCEPROP 1 LAST MATERIAL NFET
J 0
(-5475 3850);
DISPLAY 0.617021 (-5475 3850);
PAINT SKYBLUE (-5475 3850);
FORCEPROP 1 LAST LOCATION Q8G1
J 0
(-5475 3950);
DISPLAY 0.617021 (-5475 3950);
PAINT AQUA (-5475 3950);
FORCEPROP 1 LASTPIN (-5650 4100) $PN 5
J 2
(-5662 4075);
DISPLAY 0.617021 (-5662 4075);
PAINT WHITE (-5662 4075);
FORCEPROP 1 LAST VALUE BSZ019N03LS
J 0
(-5475 3900);
DISPLAY 0.617021 (-5475 3900);
PAINT SKYBLUE (-5475 3900);
FORCEPROP 1 LAST PART_NUMBER G26762-001
J 0
(-5475 3750);
DISPLAY 0.617021 (-5475 3750);
PAINT BLUE (-5475 3750);
FORCEPROP 2 LAST CDS_LIB mstr_discrete
J 0
(-5650 3900);
PAINT ORANGE (-5650 3900);
DISPLAY INVISIBLE (-5650 3900);
FORCEPROP 1 LAST PACK_TYPE LCC3
J 0
(-5475 3800);
DISPLAY 0.978723 (-5475 3800);
PAINT SKYBLUE (-5475 3800);
DISPLAY INVISIBLE (-5475 3800);
FORCEPROP 2 LAST SEC_TYPE LCC3
J 0
(-5475 4050);
DISPLAY 1.021277 (-5475 4050);
PAINT ORANGE (-5475 4050);
DISPLAY INVISIBLE (-5475 4050);
FORCEPROP 2 LAST SEC 1
J 0
(-5475 4050);
DISPLAY 0.680851 (-5475 4050);
PAINT MONO (-5475 4050);
DISPLAY INVISIBLE (-5475 4050);
FORCEPROP 1 LAST PATH I85
J 0
(-5475 4000);
DISPLAY 0.978723 (-5475 4000);
PAINT BLUE (-5475 4000);
DISPLAY INVISIBLE (-5475 4000);
FORCEPROP 2 LAST CDS_LOCATION Q8G1
J 0
(-5475 3950);
DISPLAY 0.617021 (-5475 3950);
PAINT AQUA (-5475 3950);
DISPLAY INVISIBLE (-5475 3950);
FORCEADD MOSFET_N..3
R 2
(-1375 1850);
FORCEPROP 1 LASTPIN (-1575 1950) $PN 4
J 2
(-1572 1965);
DISPLAY 0.617021 (-1572 1965);
PAINT WHITE (-1572 1965);
FORCEPROP 1 LASTPIN (-1375 1650) $PN 1
J 2
(-1387 1645);
DISPLAY 0.617021 (-1387 1645);
PAINT WHITE (-1387 1645);
FORCEPROP 1 LAST MATERIAL NFET
J 0
(-1200 1800);
DISPLAY 0.617021 (-1200 1800);
PAINT SKYBLUE (-1200 1800);
FORCEPROP 1 LAST LOCATION Q1B1
J 0
(-1200 1900);
DISPLAY 0.617021 (-1200 1900);
PAINT AQUA (-1200 1900);
FORCEPROP 1 LAST VALUE BSZ019N03LS
J 0
(-1200 1850);
DISPLAY 0.617021 (-1200 1850);
PAINT SKYBLUE (-1200 1850);
FORCEPROP 1 LAST PART_NUMBER G26762-001
J 0
(-1200 1700);
DISPLAY 0.617021 (-1200 1700);
PAINT BLUE (-1200 1700);
FORCEPROP 1 LASTPIN (-1375 2050) $PN 5
J 2
(-1387 2025);
DISPLAY 0.617021 (-1387 2025);
PAINT WHITE (-1387 2025);
FORCEPROP 2 LAST CDS_LIB mstr_discrete
J 0
(-1375 1850);
PAINT ORANGE (-1375 1850);
DISPLAY INVISIBLE (-1375 1850);
FORCEPROP 1 LAST PATH I86
J 0
(-1200 1950);
DISPLAY 0.978723 (-1200 1950);
PAINT BLUE (-1200 1950);
DISPLAY INVISIBLE (-1200 1950);
FORCEPROP 2 LAST CDS_LOCATION Q1B1
J 0
(-1200 1900);
DISPLAY 0.617021 (-1200 1900);
PAINT AQUA (-1200 1900);
DISPLAY INVISIBLE (-1200 1900);
FORCEPROP 2 LAST SEC 1
J 0
(-1200 2000);
DISPLAY 0.680851 (-1200 2000);
PAINT MONO (-1200 2000);
DISPLAY INVISIBLE (-1200 2000);
FORCEPROP 2 LAST SEC_TYPE LCC3
J 0
(-1200 2000);
DISPLAY 1.021277 (-1200 2000);
PAINT ORANGE (-1200 2000);
DISPLAY INVISIBLE (-1200 2000);
FORCEPROP 1 LAST PACK_TYPE LCC3
J 0
(-1200 1750);
DISPLAY 0.978723 (-1200 1750);
PAINT SKYBLUE (-1200 1750);
DISPLAY INVISIBLE (-1200 1750);
FORCEADD MOSFET_N..3
R 2
(-1600 3850);
FORCEPROP 1 LASTPIN (-1800 3950) $PN 4
J 2
(-1797 3965);
DISPLAY 0.617021 (-1797 3965);
PAINT WHITE (-1797 3965);
FORCEPROP 1 LASTPIN (-1600 4050) $PN 5
J 2
(-1612 4025);
DISPLAY 0.617021 (-1612 4025);
PAINT WHITE (-1612 4025);
FORCEPROP 1 LAST LOCATION Q8B1
J 0
(-1425 3900);
DISPLAY 0.617021 (-1425 3900);
PAINT AQUA (-1425 3900);
FORCEPROP 1 LASTPIN (-1600 3650) $PN 1
J 2
(-1612 3645);
DISPLAY 0.617021 (-1612 3645);
PAINT WHITE (-1612 3645);
FORCEPROP 1 LAST PART_NUMBER G26762-001
J 0
(-1425 3700);
DISPLAY 0.617021 (-1425 3700);
PAINT BLUE (-1425 3700);
FORCEPROP 1 LAST MATERIAL NFET
J 0
(-1425 3800);
DISPLAY 0.617021 (-1425 3800);
PAINT SKYBLUE (-1425 3800);
FORCEPROP 1 LAST VALUE BSZ019N03LS
J 0
(-1425 3850);
DISPLAY 0.617021 (-1425 3850);
PAINT SKYBLUE (-1425 3850);
FORCEPROP 2 LAST CDS_LIB mstr_discrete
J 0
(-1600 3850);
PAINT ORANGE (-1600 3850);
DISPLAY INVISIBLE (-1600 3850);
FORCEPROP 1 LAST PACK_TYPE LCC3
J 0
(-1425 3750);
DISPLAY 0.978723 (-1425 3750);
PAINT SKYBLUE (-1425 3750);
DISPLAY INVISIBLE (-1425 3750);
FORCEPROP 2 LAST CDS_LOCATION Q8B1
J 0
(-1425 3900);
DISPLAY 0.617021 (-1425 3900);
PAINT AQUA (-1425 3900);
DISPLAY INVISIBLE (-1425 3900);
FORCEPROP 2 LAST SEC 1
J 0
(-1425 4000);
DISPLAY 0.680851 (-1425 4000);
PAINT MONO (-1425 4000);
DISPLAY INVISIBLE (-1425 4000);
FORCEPROP 2 LAST SEC_TYPE LCC3
J 0
(-1425 4000);
DISPLAY 1.021277 (-1425 4000);
PAINT ORANGE (-1425 4000);
DISPLAY INVISIBLE (-1425 4000);
FORCEPROP 1 LAST PATH I87
J 0
(-1425 3950);
DISPLAY 0.978723 (-1425 3950);
PAINT BLUE (-1425 3950);
DISPLAY INVISIBLE (-1425 3950);
FORCEADD MOSFET_N..3
R 2
(-5325 1850);
FORCEPROP 1 LASTPIN (-5525 1950) $PN 4
J 2
(-5522 1965);
DISPLAY 0.617021 (-5522 1965);
PAINT WHITE (-5522 1965);
FORCEPROP 1 LASTPIN (-5325 1650) $PN 1
J 2
(-5337 1645);
DISPLAY 0.617021 (-5337 1645);
PAINT WHITE (-5337 1645);
FORCEPROP 1 LAST MATERIAL NFET
J 0
(-5150 1800);
DISPLAY 0.617021 (-5150 1800);
PAINT SKYBLUE (-5150 1800);
FORCEPROP 1 LAST PART_NUMBER G26762-001
J 0
(-5150 1700);
DISPLAY 0.617021 (-5150 1700);
PAINT BLUE (-5150 1700);
FORCEPROP 1 LASTPIN (-5325 2050) $PN 5
J 2
(-5337 2025);
DISPLAY 0.617021 (-5337 2025);
PAINT WHITE (-5337 2025);
FORCEPROP 1 LAST LOCATION Q7E7
J 0
(-5150 1900);
DISPLAY 0.617021 (-5150 1900);
PAINT AQUA (-5150 1900);
FORCEPROP 1 LAST VALUE BSZ019N03LS
J 0
(-5150 1850);
DISPLAY 0.617021 (-5150 1850);
PAINT SKYBLUE (-5150 1850);
FORCEPROP 1 LAST PACK_TYPE LCC3
J 0
(-5150 1750);
DISPLAY 0.978723 (-5150 1750);
PAINT SKYBLUE (-5150 1750);
DISPLAY INVISIBLE (-5150 1750);
FORCEPROP 2 LAST CDS_LIB mstr_discrete
J 0
(-5325 1850);
PAINT ORANGE (-5325 1850);
DISPLAY INVISIBLE (-5325 1850);
FORCEPROP 1 LAST PATH I88
J 0
(-5150 1950);
DISPLAY 0.978723 (-5150 1950);
PAINT BLUE (-5150 1950);
DISPLAY INVISIBLE (-5150 1950);
FORCEPROP 2 LAST CDS_LOCATION Q7E7
J 0
(-5150 1900);
DISPLAY 0.617021 (-5150 1900);
PAINT AQUA (-5150 1900);
DISPLAY INVISIBLE (-5150 1900);
FORCEPROP 2 LAST SEC 1
J 0
(-5150 2000);
DISPLAY 0.680851 (-5150 2000);
PAINT MONO (-5150 2000);
DISPLAY INVISIBLE (-5150 2000);
FORCEPROP 2 LAST SEC_TYPE LCC3
J 0
(-5150 2000);
DISPLAY 1.021277 (-5150 2000);
PAINT ORANGE (-5150 2000);
DISPLAY INVISIBLE (-5150 2000);
FORCEADD P5V_STBY..1
(-3950 4350);
FORCEPROP 3 LASTPIN (-3950 4300) SIG_NAME P5V_STBY\g
J 0
(-3940 4310);
DISPLAY 0.659574 (-3940 4310);
PAINT MONO (-3940 4310);
DISPLAY INVISIBLE (-3940 4310);
FORCEPROP 1 LAST VOLTAGE 5.0V
J 0
(-3995 4307);
DISPLAY 0.340426 (-3995 4307);
PAINT SKYBLUE (-3995 4307);
DISPLAY INVISIBLE (-3995 4307);
FORCEPROP 2 LAST CDS_LIB mstr_symbols
J 0
(-3950 4350);
PAINT ORANGE (-3950 4350);
DISPLAY INVISIBLE (-3950 4350);
FORCEPROP 1 LAST PATH I9
J 0
(-3905 4352);
DISPLAY 0.340426 (-3905 4352);
PAINT GREEN (-3905 4352);
DISPLAY INVISIBLE (-3905 4352);
FORCEPROP 1 LAST SIZE 1B
J 0
(-3905 4372);
DISPLAY 0.340426 (-3905 4372);
PAINT GREEN (-3905 4372);
DISPLAY INVISIBLE (-3905 4372);
FORCEPROP 1 LAST BODY_TYPE PLUMBING
J 0
(-3995 4307);
DISPLAY 0.340426 (-3995 4307);
PAINT GREEN (-3995 4307);
DISPLAY INVISIBLE (-3995 4307);
FORCEPROP 1 LAST HDL_POWER P5V_STBY
J 0
(-4250 4225);
DISPLAY 0.872340 (-4250 4225);
PAINT ORANGE (-4250 4225);
DISPLAY INVISIBLE (-4250 4225);
FORCEADD DNS..2
(-6920 3045);
PAINT RED (-6920 3045);
FORCEPROP 2 LAST CDS_LIB mstr_misc
J 0
(-6920 3045);
PAINT ORANGE (-6920 3045);
DISPLAY INVISIBLE (-6920 3045);
FORCEPROP 1 LAST COMMENT_BODY TRUE
R 1
J 0
(-6845 2820);
DISPLAY 0.872340 (-6845 2820);
PAINT GREEN (-6845 2820);
DISPLAY INVISIBLE (-6845 2820);
FORCEADD INTEL_CORP_BPAGE..1
(-275 300);
FORCEPROP 1 LAST CDS_CON_LAST_MODIFIED Fri Jun 16 17:49:12 2017
J 0
(-1700 625);
PAINT GREEN (-1700 625);
DISPLAY INVISIBLE (-1700 625);
FORCEPROP 1 LAST CUSTOM_TXT_CDS <CURRENT_DESIGN_SHEET> OF <TOTAL_DESIGN_SHEETS>
J 0
(-775 325);
PAINT ORANGE (-775 325);
FORCEPROP 1 LAST CUSTOM_TXT_CDS <CON_LAST_MODIFIED>
J 0
(-4275 400);
PAINT ORANGE (-4275 400);
FORCEPROP 2 LAST CUSTOM_TXT_CDS <XR_PAGE_TITLE>
J 0
(-8165 5550);
DISPLAY 0.638298 (-8165 5550);
PAINT PINK (-8165 5550);
DISPLAY INVISIBLE (-8165 5550);
FORCEPROP 1 LAST SCH_TITLE POWER SWITCHES
J 0
(-8075 450);
DISPLAY 1.212766 (-8075 450);
PAINT ORANGE (-8075 450);
FORCEPROP 2 LAST PAGE_BORDER TRUE
J 0
(-8165 5550);
DISPLAY 0.851064 (-8165 5550);
PAINT PINK (-8165 5550);
DISPLAY INVISIBLE (-8165 5550);
FORCEPROP 2 LAST CDS_LIB mstr_symbols
J 0
(-275 300);
PAINT ORANGE (-275 300);
DISPLAY INVISIBLE (-275 300);
FORCEPROP 1 LAST COMMENT_BODY TRUE
J 0
(-263 312);
DISPLAY 0.468085 (-263 312);
PAINT GREEN (-263 312);
DISPLAY INVISIBLE (-263 312);
FORCEPROP 2 LAST CDS_XR_PAGE_TITLE CR-198 : @BASEBOARD_FAB2_LIB.BASEBOARD_FAB2(SCH_1):PAGE198
J 0
(-8165 5550);
DISPLAY 0.638298 (-8165 5550);
PAINT PINK (-8165 5550);
DISPLAY INVISIBLE (-8165 5550);
WIRE 16 -1 (-2775 3600)(-2775 3475);
WIRE 16 -1 (-2775 3650)(-2775 3600);
WIRE 16 -1 (-3000 3600)(-2775 3600);
WIRE 16 -1 (-3000 3650)(-2775 3650);
WIRE 16 -1 (-7375 2350)(-7375 2475);
WIRE 16 -1 (-7375 2000)(-7375 2350);
WIRE 16 -1 (-7725 2350)(-7375 2350);
WIRE 16 -1 (-7725 2275)(-7725 2350);
WIRE 16 -1 (-7375 2000)(-7150 2000);
WIRE 16 -1 (-7150 2000)(-7150 1800);
WIRE 16 -1 (-7025 2000)(-7150 2000);
WIRE 16 -1 (-7150 1800)(-7025 1800);
WIRE 16 -1 (-6200 1650)(-6200 1525);
WIRE 16 -1 (-6200 1700)(-6200 1650);
WIRE 16 -1 (-6425 1650)(-6200 1650);
WIRE 16 -1 (-6425 1700)(-6200 1700);
WIRE 16 -1 (-7650 4350)(-7650 4475);
WIRE 16 -1 (-7650 3975)(-7650 4350);
WIRE 16 -1 (-8000 4350)(-7650 4350);
WIRE 16 -1 (-8000 4300)(-8000 4350);
WIRE 16 -1 (-7475 3975)(-7650 3975);
WIRE 16 -1 (-7475 3975)(-7475 3775);
WIRE 16 -1 (-7300 3975)(-7475 3975);
WIRE 16 -1 (-7300 3775)(-7475 3775);
WIRE 16 -1 (-1600 4600)(-1600 4675);
WIRE 16 -1 (-1600 4225)(-1600 4600);
WIRE 16 -1 (-1375 4600)(-1600 4600);
WIRE 16 -1 (-1050 4600)(-1375 4600);
WIRE 16 -1 (-1375 4500)(-1375 4600);
WIRE 16 -1 (-1850 4225)(-1600 4225);
WIRE 16 -1 (-1600 4225)(-1600 4050);
WIRE 16 -1 (-1850 3850)(-1850 4225);
WIRE 16 -1 (-1050 4500)(-1050 4600);
WIRE 16 -1 (-3000 3850)(-1850 3850);
WIRE 16 -1 (-1100 3550)(-1100 3450);
WIRE 16 -1 (-1100 3450)(-1100 3400);
WIRE 16 -1 (-775 3450)(-1100 3450);
WIRE 16 -1 (-775 3350)(-775 3450);
WIRE 16 -1 (-1600 3400)(-1100 3400);
WIRE 16 -1 (-1100 3350)(-1100 3400);
WIRE 16 -1 (-1850 3400)(-1600 3400);
WIRE 16 -1 (-1600 3650)(-1600 3400);
WIRE 16 -1 (-1850 3750)(-1850 3400);
WIRE 16 -1 (-3000 3750)(-1850 3750);
WIRE 16 -1 (-4675 1575)(-4675 1450);
WIRE 16 -1 (-5125 1450)(-4675 1450);
WIRE 16 -1 (-4675 1300)(-4675 1450);
WIRE 16 -1 (-5325 1450)(-5125 1450);
WIRE 16 -1 (-5125 1350)(-5125 1450);
WIRE 16 -1 (-5650 1450)(-5325 1450);
WIRE 16 -1 (-5325 1650)(-5325 1450);
WIRE 16 -1 (-5650 1800)(-5650 1450);
WIRE 16 -1 (-6425 1800)(-5650 1800);
WIRE 16 -1 (-5325 2450)(-5325 2525);
WIRE 16 -1 (-5325 2275)(-5325 2450);
WIRE 16 -1 (-5100 2450)(-5325 2450);
WIRE 16 -1 (-4775 2450)(-5100 2450);
WIRE 16 -1 (-5100 2350)(-5100 2450);
WIRE 16 -1 (-5650 2275)(-5325 2275);
WIRE 16 -1 (-5325 2275)(-5325 2050);
WIRE 16 -1 (-5650 1900)(-5650 2275);
WIRE 16 -1 (-4775 2350)(-4775 2450);
WIRE 16 -1 (-6425 1900)(-5650 1900);
WIRE 16 -1 (-8000 4050)(-8000 4100);
WIRE 16 -1 (-4300 4000)(-4300 4025);
WIRE 16 -1 (-7725 2050)(-7725 2075);
WIRE 16 -1 (-6475 3625)(-6475 3500);
WIRE 16 -1 (-6475 3675)(-6475 3625);
WIRE 16 -1 (-6700 3625)(-6475 3625);
WIRE 16 -1 (-6700 3675)(-6475 3675);
WIRE 16 -1 (-1200 4125)(-1200 4175);
WIRE 16 -1 (-1050 4175)(-1200 4175);
WIRE 16 -1 (-1200 4175)(-1375 4175);
WIRE 16 -1 (-1375 4175)(-1375 4300);
WIRE 16 -1 (-1050 4300)(-1050 4175);
WIRE 16 -1 (-925 2950)(-925 3025);
WIRE 16 -1 (-775 3025)(-925 3025);
WIRE 16 -1 (-925 3025)(-1100 3025);
WIRE 16 -1 (-1100 3150)(-1100 3025);
WIRE 16 -1 (-775 3150)(-775 3025);
WIRE 16 -1 (-5075 3975)(-5075 4050);
WIRE 16 -1 (-5075 4050)(-5375 4050);
WIRE 16 -1 (-5050 4050)(-5075 4050);
WIRE 16 -1 (-5050 4175)(-5050 4050);
WIRE 16 -1 (-5375 4050)(-5375 4175);
WIRE 16 -1 (-4775 2900)(-4775 3000);
WIRE 16 -1 (-4775 3000)(-5000 3000);
WIRE 16 -1 (-4675 3000)(-4775 3000);
WIRE 16 -1 (-4675 3100)(-4675 3000);
WIRE 16 -1 (-5000 3000)(-5000 3100);
WIRE 16 -1 (-5125 975)(-5125 1025);
WIRE 16 -1 (-4675 1025)(-5125 1025);
WIRE 16 -1 (-5125 1025)(-5125 1150);
WIRE 16 -1 (-4675 1100)(-4675 1025);
WIRE 16 -1 (-4800 1950)(-4800 2025);
WIRE 16 -1 (-4800 2025)(-5100 2025);
WIRE 16 -1 (-4775 2025)(-4800 2025);
WIRE 16 -1 (-4775 2150)(-4775 2025);
WIRE 16 -1 (-5100 2025)(-5100 2150);
WIRE 16 -1 (-5600 4475)(-5600 4550);
WIRE 16 -1 (-5600 4250)(-5600 4475);
WIRE 16 -1 (-5375 4475)(-5600 4475);
WIRE 16 -1 (-5050 4475)(-5375 4475);
WIRE 16 -1 (-5375 4375)(-5375 4475);
WIRE 16 -1 (-5650 4250)(-5600 4250);
WIRE 16 -1 (-5950 4250)(-5650 4250);
WIRE 16 -1 (-5650 4250)(-5650 4100);
WIRE 16 -1 (-5050 4375)(-5050 4475);
WIRE 16 -1 (-5950 3875)(-5950 4250);
WIRE 16 -1 (-6700 3875)(-5950 3875);
WIRE 16 -1 (-1175 950)(-1175 1000);
WIRE 16 -1 (-725 1000)(-1175 1000);
WIRE 16 -1 (-1175 1000)(-1175 1125);
WIRE 16 -1 (-725 1125)(-725 1000);
WIRE 16 -1 (-3775 2000)(-3775 2050);
WIRE 16 -1 (-3425 2325)(-3425 2450);
WIRE 16 -1 (-3425 1975)(-3425 2325);
WIRE 16 -1 (-3775 2325)(-3425 2325);
WIRE 16 -1 (-3775 2250)(-3775 2325);
WIRE 16 -1 (-3425 1975)(-3200 1975);
WIRE 16 -1 (-3200 1975)(-3200 1775);
WIRE 16 -1 (-3075 1975)(-3200 1975);
WIRE 16 -1 (-3200 1775)(-3075 1775);
WIRE 16 -1 (-5125 3625)(-5125 3425);
WIRE 16 -1 (-5650 3425)(-5125 3425);
WIRE 16 -1 (-5125 3425)(-5000 3425);
WIRE 16 -1 (-4675 3425)(-5000 3425);
WIRE 16 -1 (-5000 3300)(-5000 3425);
WIRE 16 -1 (-5950 3425)(-5650 3425);
WIRE 16 -1 (-5650 3700)(-5650 3425);
WIRE 16 -1 (-5950 3775)(-5950 3425);
WIRE 16 -1 (-4675 3300)(-4675 3425);
WIRE 16 -1 (-6700 3775)(-5950 3775);
WIRE 16 -1 (-2250 1625)(-2250 1500);
WIRE 16 -1 (-2250 1675)(-2250 1625);
WIRE 16 -1 (-2475 1625)(-2250 1625);
WIRE 16 -1 (-2475 1675)(-2250 1675);
WIRE 16 -1 (-1375 2425)(-1375 2500);
WIRE 16 -1 (-1375 2250)(-1375 2425);
WIRE 16 -1 (-1150 2425)(-1375 2425);
WIRE 16 -1 (-825 2425)(-1150 2425);
WIRE 16 -1 (-1150 2325)(-1150 2425);
WIRE 16 -1 (-1700 2250)(-1375 2250);
WIRE 16 -1 (-1375 2250)(-1375 2050);
WIRE 16 -1 (-1700 1875)(-1700 2250);
WIRE 16 -1 (-825 2325)(-825 2425);
WIRE 16 -1 (-2475 1875)(-1700 1875);
WIRE 16 -1 (-850 1950)(-850 2000);
WIRE 16 -1 (-850 2000)(-825 2000);
WIRE 16 -1 (-1150 2000)(-850 2000);
WIRE 16 -1 (-1150 2000)(-1150 2125);
WIRE 16 -1 (-825 2125)(-825 2000);
WIRE 16 -1 (-725 1550)(-725 1425);
WIRE 16 -1 (-1175 1425)(-725 1425);
WIRE 16 -1 (-725 1425)(-725 1325);
WIRE 16 -1 (-1375 1425)(-1175 1425);
WIRE 16 -1 (-1175 1325)(-1175 1425);
WIRE 16 -1 (-1700 1425)(-1375 1425);
WIRE 16 -1 (-1375 1650)(-1375 1425);
WIRE 16 -1 (-1700 1775)(-1700 1425);
WIRE 16 -1 (-2475 1775)(-1700 1775);
WIRE 16 -1 (-6925 3150)(-6925 3225);
WIRE 16 -1 (-6850 2475)(-6850 2525);
WIRE 16 -1 (-3950 4250)(-3950 4300);
WIRE 16 -1 (-3950 3950)(-3950 4250);
WIRE 16 -1 (-4300 4250)(-3950 4250);
WIRE 16 -1 (-4300 4225)(-4300 4250);
WIRE 16 -1 (-3775 3950)(-3950 3950);
WIRE 16 -1 (-3775 3750)(-3775 3950);
WIRE 16 -1 (-3600 3950)(-3775 3950);
WIRE 16 -1 (-3600 3750)(-3775 3750);
WIRE 16 -1 (-5900 4000)(-5850 4000);
WIRE 16 -1 (-5900 3825)(-5900 4000);
WIRE 16 -1 (-6700 3825)(-5900 3825);
FORCEPROP 0 LAST VOLTAGE 3.3
J 0
(-6550 3900);
DISPLAY 1.021277 (-6550 3900);
PAINT SKYBLUE (-6550 3900);
DISPLAY INVISIBLE (-6550 3900);
FORCEPROP 0 LAST SIG_NAME P3V3_SWITCH_G
J 0
(-6560 3835);
DISPLAY 0.617021 (-6560 3835);
PAINT ORANGE (-6560 3835);
FORCEPROP 2 LASTPROP $XRERR UNIQUE?
J 0
(-6800 3835);
DISPLAY 0.638298 (-6800 3835);
PAINT MONO (-6800 3835);
DISPLAY INVISIBLE (-6800 3835);
WIRE 16 -1 (-7300 3875)(-7875 3875);
FORCEPROP 0 LAST SIG_NAME FM_P3V3_CPLD_EN
J 0
(-7860 3885);
DISPLAY 0.617021 (-7860 3885);
PAINT ORANGE (-7860 3885);
WIRE 16 -1 (-6700 3975)(-6250 3975);
FORCEPROP 0 LAST SIG_NAME TP_SLG55021_P3V3_8
J 0
(-6635 3985);
DISPLAY 0.617021 (-6635 3985);
PAINT ORANGE (-6635 3985);
FORCEPROP 2 LASTPROP $XRERR UNIQUE?
J 0
(-6220 3975);
DISPLAY 0.638298 (-6220 3975);
PAINT MONO (-6220 3975);
DISPLAY INVISIBLE (-6220 3975);
WIRE 16 -1 (-3075 1875)(-3925 1875);
FORCEPROP 0 LAST SIG_NAME FM_ENABLE_FAN_POWER
J 0
(-3885 1885);
DISPLAY 0.617021 (-3885 1885);
PAINT ORANGE (-3885 1885);
WIRE 16 -1 (-2475 1975)(-1975 1975);
FORCEPROP 0 LAST SIG_NAME TP_SLG55021_P12V_FAN_8
J 0
(-2410 1985);
DISPLAY 0.617021 (-2410 1985);
PAINT ORANGE (-2410 1985);
FORCEPROP 2 LASTPROP $XRERR UNIQUE?
J 0
(-1945 1975);
DISPLAY 0.638298 (-1945 1975);
PAINT MONO (-1945 1975);
DISPLAY INVISIBLE (-1945 1975);
WIRE 16 -1 (-1625 1950)(-1575 1950);
WIRE 16 -1 (-1625 1825)(-2475 1825);
FORCEPROP 0 LAST VOLTAGE +5V
J 0
(-2325 1900);
DISPLAY 1.021277 (-2325 1900);
PAINT SKYBLUE (-2325 1900);
DISPLAY INVISIBLE (-2325 1900);
FORCEPROP 0 LAST SIG_NAME P12V_FAN_SWITCH_G
J 0
(-2335 1835);
DISPLAY 0.617021 (-2335 1835);
PAINT ORANGE (-2335 1835);
FORCEPROP 2 LASTPROP $XRERR UNIQUE?
J 0
(-2575 1835);
DISPLAY 0.638298 (-2575 1835);
PAINT MONO (-2575 1835);
DISPLAY INVISIBLE (-2575 1835);
WIRE 16 -1 (-1625 1825)(-1625 1950);
WIRE 16 -1 (-1825 3950)(-1800 3950);
WIRE 16 -1 (-1825 3800)(-1825 3950);
WIRE 16 -1 (-3000 3800)(-1825 3800);
FORCEPROP 0 LAST VOLTAGE +5V
J 0
(-2850 3875);
DISPLAY 1.021277 (-2850 3875);
PAINT SKYBLUE (-2850 3875);
DISPLAY INVISIBLE (-2850 3875);
FORCEPROP 0 LAST SIG_NAME P5V_SWITCH_G
J 0
(-2860 3810);
DISPLAY 0.617021 (-2860 3810);
PAINT ORANGE (-2860 3810);
FORCEPROP 2 LASTPROP $XRERR UNIQUE?
J 0
(-3100 3810);
DISPLAY 0.638298 (-3100 3810);
PAINT MONO (-3100 3810);
DISPLAY INVISIBLE (-3100 3810);
WIRE 16 -1 (-5550 1950)(-5525 1950);
WIRE 16 -1 (-5550 1850)(-5550 1950);
WIRE 16 -1 (-6425 1850)(-5550 1850);
FORCEPROP 0 LAST VOLTAGE +3.3V
J 0
(-6275 1925);
DISPLAY 1.021277 (-6275 1925);
PAINT SKYBLUE (-6275 1925);
DISPLAY INVISIBLE (-6275 1925);
FORCEPROP 0 LAST SIG_NAME P12V_SWITCH_G
J 0
(-6210 1860);
DISPLAY 0.617021 (-6210 1860);
PAINT ORANGE (-6210 1860);
FORCEPROP 2 LASTPROP $XRERR UNIQUE?
J 0
(-6450 1860);
DISPLAY 0.638298 (-6450 1860);
PAINT MONO (-6450 1860);
DISPLAY INVISIBLE (-6450 1860);
WIRE 16 -1 (-6425 2000)(-6300 2000);
FORCEPROP 2 LAST SIG_NAME TP_SLG55021_P12V_MAIN_8
J 0
(-6360 2010);
DISPLAY 0.617021 (-6360 2010);
PAINT ORANGE (-6360 2010);
FORCEPROP 2 LASTPROP $XRERR UNIQUE?
J 0
(-6270 2000);
DISPLAY 0.638298 (-6270 2000);
PAINT MONO (-6270 2000);
DISPLAY INVISIBLE (-6270 2000);
WIRE 16 -1 (-7025 1900)(-7875 1900);
FORCEPROP 0 LAST SIG_NAME FM_P12V_MAIN_SW_EN
J 0
(-7844 1926);
DISPLAY 0.617021 (-7844 1926);
PAINT ORANGE (-7844 1926);
WIRE 16 -1 (-3000 3950)(-2500 3950);
FORCEPROP 0 LAST SIG_NAME TP_SLG55021_P5V_8
J 0
(-2935 3960);
DISPLAY 0.617021 (-2935 3960);
PAINT ORANGE (-2935 3960);
FORCEPROP 2 LASTPROP $XRERR UNIQUE?
J 0
(-2470 3950);
DISPLAY 0.638298 (-2470 3950);
PAINT MONO (-2470 3950);
DISPLAY INVISIBLE (-2470 3950);
WIRE 16 -1 (-7600 2800)(-6925 2800);
FORCEPROP 0 LAST SIG_NAME FM_CTNR_PS_ON
J 0
(-7560 2810);
DISPLAY 0.617021 (-7560 2810);
PAINT ORANGE (-7560 2810);
WIRE 16 -1 (-6925 2950)(-6925 2800);
WIRE 16 -1 (-6850 2800)(-6925 2800);
WIRE 16 -1 (-6850 2725)(-6850 2800);
WIRE 16 -1 (-4300 2800)(-6850 2800);
WIRE 16 -1 (-4300 2800)(-4300 3850);
WIRE 16 -1 (-3600 3850)(-4300 3850);
DOT 1 (-850 2000);
DOT 1 (-3425 2325);
DOT 1 (-5100 2450);
DOT 1 (-1150 2425);
DOT 1 (-1200 4175);
DOT 1 (-1375 4600);
DOT 1 (-1600 4600);
DOT 1 (-1600 4225);
DOT 1 (-3950 4250);
DOT 1 (-925 3025);
DOT 1 (-1100 3450);
DOT 1 (-1100 3400);
DOT 1 (-1600 3400);
DOT 1 (-1375 2425);
DOT 1 (-1375 2250);
DOT 1 (-725 1425);
DOT 1 (-1175 1425);
DOT 1 (-1375 1425);
DOT 1 (-1175 1000);
DOT 1 (-2775 3600);
DOT 1 (-3775 3950);
DOT 1 (-2250 1625);
DOT 1 (-3200 1975);
DOT 1 (-5375 4475);
DOT 1 (-5600 4475);
DOT 1 (-5650 4250);
DOT 1 (-7650 4350);
DOT 1 (-5075 4050);
DOT 1 (-5000 3425);
DOT 1 (-4775 3000);
DOT 1 (-5125 3425);
DOT 1 (-5650 3425);
DOT 1 (-5325 2450);
DOT 1 (-5325 2275);
DOT 1 (-4800 2025);
DOT 1 (-4675 1450);
DOT 1 (-5325 1450);
DOT 1 (-5125 1450);
DOT 1 (-5125 1025);
DOT 1 (-6475 3625);
DOT 1 (-6850 2800);
DOT 1 (-6925 2800);
DOT 1 (-7475 3975);
DOT 1 (-7375 2350);
DOT 1 (-6200 1650);
DOT 1 (-7150 2000);
FORCENOTE
ROOM=P5V_PWR_SWITCH
(-3625 3250) 0;
DISPLAY LEFT (-3625 3250);
DISPLAY 1.021277 (-3625 3250);
PAINT PURPLE (-3625 3250);
FORCENOTE
ROOM=P12V_FAN_PWR_SWITCH
(-3225 1225) 0;
DISPLAY LEFT (-3225 1225);
DISPLAY 1.021277 (-3225 1225);
PAINT PURPLE (-3225 1225);
FORCENOTE
ROOM=P3V3_PWR_SWITCH
(-7625 3450) 0;
DISPLAY LEFT (-7625 3450);
DISPLAY 1.021277 (-7625 3450);
PAINT PURPLE (-7625 3450);
FORCENOTE
BOM_COST=PWR_SWITCH
(-8100 600) 0;
DISPLAY LEFT (-8100 600);
DISPLAY 1.021277 (-8100 600);
PAINT PURPLE (-8100 600);
FORCENOTE
ROOM=P12V_PWR_SWITCH
(-7175 1250) 0;
DISPLAY LEFT (-7175 1250);
DISPLAY 1.021277 (-7175 1250);
PAINT PURPLE (-7175 1250);
QUIT
